G04 ================== begin FILE IDENTIFICATION RECORD ==================*
G04 Layout Name:  F:/<user>/2022/FB/R4006-TIMING/brd/gerber-3/R4006-B0001-02_R01.brd*
G04 Film Name:    R4006-B0001-02_R01_L10*
G04 File Format:  Gerber RS274X*
G04 File Origin:  Cadence Allegro 17.2-S079*
G04 Origin Date:  Fri Feb 25 18:14:43 2022*
G04 *
G04 Layer:  ETCH/BOTTOM*
G04 Layer:  PIN/BOTTOM*
G04 Layer:  VIA CLASS/BOTTOM*
G04 Layer:  MANUFACTURING/BOTTOM*
G04 Layer:  MANUFACTURING/CELESTICA_LEGEND*
G04 *
G04 Offset:    (0.00 0.00)*
G04 Mirror:    No*
G04 Mode:      Positive*
G04 Rotation:  0*
G04 FullContactRelief:  No*
G04 UndefLineWidth:     6.00*
G04 ================== end FILE IDENTIFICATION RECORD ====================*
%FSLAX55Y55*MOIN*%
%IR0*IPPOS*OFA0.00000B0.00000*MIA0B0*SFA1.00000B1.00000*%
%ADD36R,.045X.104*%
%ADD39R,.024X.005*%
%ADD12C,.02*%
%ADD25R,.005X.024*%
%ADD13C,.03*%
%ADD21C,.04*%
%ADD27R,.028X.126*%
%ADD15C,.024*%
%ADD35C,.025*%
%ADD37R,.108X.085*%
%ADD26R,.028X.165*%
%ADD11C,.09*%
%ADD10C,.018*%
%ADD46C,.057*%
%ADD16C,.086*%
%ADD38R,.015X.012*%
%ADD23C,.1*%
%ADD22R,.034X.03*%
%ADD24R,.03X.034*%
%ADD28R,.065X.02*%
%ADD42C,.104*%
%ADD32R,.02X.047*%
%ADD20R,.06X.018*%
%ADD30R,.013X.038*%
%ADD19R,.024X.028*%
%ADD14C,.115*%
%ADD18O,.075X.035*%
%ADD17R,.028X.024*%
%ADD44C,.108*%
%ADD41R,.043X.057*%
%ADD33R,.054X.038*%
%ADD45O,.075X.048*%
%ADD43R,.104X.104*%
%ADD29R,.038X.054*%
%ADD34R,.055X.039*%
%ADD40R,.039X.057*%
%ADD31C,.198*%
%ADD47C,.01*%
%ADD48C,.012*%
%ADD49C,.015*%
%ADD50C,.004*%
%ADD51C,.005*%
%ADD52C,.006*%
%ADD53C,.008*%
%ADD54C,.0036*%
%ADD55C,.0047*%
%ADD56C,.0057*%
%ADD57C,.0039*%
%ADD58C,.125*%
G75*
%LPD*%
G75*
G36*
G01X3004Y21654D02*
Y54500D01*
X4898D01*
X4998Y54400D01*
Y22714D01*
X54058D01*
Y46260D01*
G02X62992Y55194I8934J0D01*
G01X127362D01*
G02X136296Y46260I0J-8934D01*
G01Y22714D01*
X157798D01*
Y43012D01*
G02X169980Y55194I12182J0D01*
G02X181399Y47258I0J-12183D01*
G01X180286Y46145D01*
G02X179624Y46299I-283J283D01*
G03X169980Y53201I-9644J-3287D01*
G03X159791Y43012I0J-10189D01*
G01Y21654D01*
G02X158858Y20721I-933J0D01*
G01X135236D01*
G02X134303Y21654I0J933D01*
G01Y46260D01*
G03X127362Y53201I-6941J0D01*
G01X62992D01*
G03X56051Y46260I0J-6941D01*
G01Y21654D01*
G02X55118Y20721I-933J0D01*
G01X3937D01*
G02X3004Y21654I0J933D01*
G37*
G36*
G01X4737Y351333D02*
G02X4998Y351142I61J-191D01*
G01Y277500D01*
X3004D01*
Y351142D01*
G02X3265Y351332I200J0D01*
G03X3999Y351217I734J2287D01*
G01X4000D01*
G03X4737Y351333I0J2402D01*
G37*
G36*
G01X3033Y53530D02*
X56043D01*
Y21660D01*
X55126Y20743D01*
X3827D01*
X3033Y21537D01*
Y53530D01*
G37*
G36*
G01X3854Y434589D02*
X50000D01*
Y353150D01*
X3012D01*
Y433747D01*
X3854Y434589D01*
G37*
G36*
G01X50889Y432600D02*
G02X50699Y432861I1J200D01*
G03X50815Y433597I-2286J737D01*
G01Y433598D01*
G03X50814Y433658I-2402J-10D01*
G01Y434549D01*
X50859Y434594D01*
X618177D01*
Y432600D01*
X50889D01*
G37*
G36*
G01X114118Y348500D02*
X115500D01*
X116198Y347801D01*
Y346300D01*
G03X116500Y345244I2002J1D01*
G01Y344000D01*
X115500Y343000D01*
X107000D01*
X106000Y344000D01*
Y345169D01*
G03X107019Y347308I-1981J2256D01*
G01X107026Y347500D01*
X111500D01*
X112500Y348500D01*
X113885D01*
G03X114000Y348498I118J3500D01*
G03X114115Y348500I-3J3502D01*
G01X114118D01*
G37*
G36*
G01X109700Y357198D02*
G03X110750Y357496I-1J2002D01*
G03X111800Y357198I1051J1704D01*
G01X114298D01*
Y355000D01*
G03X114500Y354125I2002J1D01*
G01Y351500D01*
X113676Y350676D01*
X113616Y350664D01*
G03X113128Y350502I381J-1965D01*
G01X111671D01*
X110671Y349502D01*
X107498D01*
X107000Y350000D01*
Y354125D01*
G03X107202Y355000I-1800J876D01*
G01Y357198D01*
X109700D01*
G37*
G36*
G01X155567Y106043D02*
G03I-12000J0D01*
G37*
G36*
G01X158067Y268043D02*
G03I-12000J0D01*
G37*
G36*
G01X167300Y401300D02*
X166193D01*
X163500D01*
X163300Y401500D01*
Y405700D01*
X163583Y405983D01*
X165704D01*
G02X165819Y406000I115J-383D01*
G01X167400D01*
X167700Y405700D01*
Y401700D01*
X167300Y401300D01*
G37*
G36*
G01X158900D02*
X160007D01*
X162700D01*
X162900Y401500D01*
Y405700D01*
Y406400D01*
X162300Y407000D01*
X159000D01*
X158500Y406500D01*
Y405700D01*
Y401700D01*
X158900Y401300D01*
G37*
G36*
G01X190500Y32500D02*
X188500Y30500D01*
Y28500D01*
X188000Y28000D01*
X183000D01*
X182400Y28600D01*
Y38200D01*
X183300Y39100D01*
X187400D01*
X190500Y36000D01*
Y32500D01*
G37*
G36*
G01X222256Y62500D02*
X228500D01*
Y53500D01*
X216000Y41000D01*
Y29500D01*
X215000Y28500D01*
X208000D01*
X207500Y29000D01*
Y42000D01*
X214500Y49000D01*
Y51169D01*
G03Y56831I-1001J2831D01*
G01Y62198D01*
X216700D01*
G03X217750Y62496I-1J2002D01*
G03X218800Y62198I1051J1704D01*
G01X221200D01*
G03X222256Y62500I-1J2002D01*
G37*
G36*
G01X207300Y399400D02*
X226000D01*
X229100Y396300D01*
Y388100D01*
X226000Y385000D01*
X218000D01*
X216889Y383889D01*
X216852Y383874D01*
G03X214998Y381100I1148J-2774D01*
G03X216479Y378512I3002J0D01*
G01X216501Y378499D01*
X219400Y375600D01*
X220724D01*
X220748Y375594D01*
G03X221500Y375498I753J2906D01*
G03X222252Y375594I-1J3002D01*
G01X222276Y375600D01*
X225224D01*
X225248Y375594D01*
G03X226000Y375498I753J2906D01*
G03X226752Y375594I-1J3002D01*
G01X226776Y375600D01*
X232100D01*
X241800Y365900D01*
X258600D01*
X262000Y362500D01*
Y344500D01*
X261000Y343500D01*
X241100D01*
X240766Y343834D01*
G03X241002Y345000I-2766J1167D01*
G03X238000Y348002I-3002J0D01*
G03X236952Y347813I0J-3002D01*
G01X236832Y347768D01*
X225350Y359250D01*
X207050D01*
X202100Y364200D01*
Y394200D01*
X207300Y399400D01*
G37*
G36*
G01X230163Y73000D02*
X231500D01*
X232500Y72000D01*
Y67000D01*
X232000Y66500D01*
X223500D01*
Y72000D01*
X224500Y73000D01*
X226838D01*
G03X228500Y72498I1662J2500D01*
G03X230114Y72969I0J3001D01*
G01X230163Y73000D01*
G37*
G36*
G01X280567Y112143D02*
G03I-12000J0D01*
G37*
G36*
G01Y255943D02*
G03I-12000J0D01*
G37*
G36*
G01X272002Y221500D02*
X272660D01*
G03X275260Y219998I2600J1499D01*
G03X275406Y220002I-9J3002D01*
G01X275494Y220006D01*
X275798Y219701D01*
Y219200D01*
G03X277800Y217198I2002J0D01*
G01X280200D01*
G03X281802Y218000I0J2001D01*
G01X286500D01*
X291497Y213003D01*
X291499Y212923D01*
G03X294923Y209499I3501J77D01*
G01X295003Y209497D01*
X298500Y206000D01*
X300000D01*
X300500Y205500D01*
Y198000D01*
X302000Y196500D01*
Y186000D01*
X301796Y185796D01*
G02X301159Y185893I-283J283D01*
G03X298500Y187502I-2659J-1393D01*
G03X295669Y185500I0J-3003D01*
G01X295000D01*
X288500Y192000D01*
Y199500D01*
X286500Y201500D01*
X280500D01*
X272000Y210000D01*
Y214894D01*
G03X272002Y215000I-3000J110D01*
G03X272000Y215106I-3002J-4D01*
G01Y216926D01*
G03X272002Y217000I-2000J91D01*
G01Y221500D01*
G37*
G36*
G01X292802Y286000D02*
X321000D01*
Y281000D01*
X320000Y280000D01*
X312500D01*
X302000Y269500D01*
Y235175D01*
X301000Y234500D01*
X299500Y233000D01*
X293256D01*
G03X292200Y233302I-1057J-1700D01*
G01X289800D01*
G03X288744Y233000I1J-2002D01*
G01X282500D01*
X281765Y232265D01*
X281623Y232407D01*
G03X280200Y233002I-1424J-1407D01*
G01X277800D01*
G03X275798Y231000I0J-2002D01*
G01Y230798D01*
X273500Y228500D01*
X271500D01*
Y239000D01*
X282000Y249500D01*
Y251994D01*
X282008Y252021D01*
G03X282568Y255943I-13441J3920D01*
G03X282008Y259865I-14001J2D01*
G01X282000Y259892D01*
Y267500D01*
X281000Y268500D01*
Y283500D01*
X283099Y285599D01*
G03X284300Y285198I1202J1601D01*
G01X286700D01*
G03X287750Y285496I-1J2002D01*
G03X288800Y285198I1051J1704D01*
G01X291200D01*
G03X292802Y286000I0J2001D01*
G37*
G36*
G01X284500Y292500D02*
X289500Y297500D01*
X312500D01*
X313500Y296500D01*
Y289500D01*
X293000D01*
X292000Y288500D01*
X284500D01*
Y292500D01*
G37*
G36*
G01X303302Y206000D02*
X311500D01*
X312500Y205000D01*
Y192500D01*
X312000Y192000D01*
X305000D01*
Y198000D01*
X303302Y199698D01*
Y201700D01*
G03X303004Y202750I-2002J-1D01*
G03X303302Y203800I-1704J1051D01*
G01Y206000D01*
G37*
G36*
G01X618926Y55194D02*
G02X619116Y54933I-1J-200D01*
G01Y53320D01*
X618998Y53202D01*
X316437D01*
X316286Y53353D01*
Y55030D01*
X316450Y55194D01*
X618926D01*
G37*
G36*
G01X316000Y296000D02*
X317000Y297000D01*
X324500D01*
X325500Y296000D01*
Y289500D01*
X322000D01*
X321500Y290000D01*
X316000D01*
Y296000D01*
G37*
G36*
G01X332600Y396500D02*
X333707D01*
X336400D01*
X336600Y396300D01*
Y392100D01*
Y391700D01*
X335400Y390500D01*
X324300D01*
Y396000D01*
X324800Y396500D01*
X332600D01*
G37*
G36*
G01X341000D02*
X339893D01*
X337200D01*
X337000Y396300D01*
Y392100D01*
Y391400D01*
X337600Y390800D01*
X340900D01*
X341400Y391300D01*
Y392100D01*
Y396100D01*
X341000Y396500D01*
G37*
G36*
G01X357500Y127200D02*
X356600Y126300D01*
X344600D01*
X343500Y127400D01*
Y133000D01*
X343950Y133450D01*
X355450D01*
X357500Y131400D01*
Y127200D01*
G37*
G36*
G01X360000Y145000D02*
X362000Y143000D01*
Y135500D01*
X356000D01*
X354500Y137000D01*
X343800D01*
X343000Y137800D01*
Y144500D01*
X343500Y145000D01*
X360000D01*
G37*
G36*
G01X362000Y227000D02*
X363000Y226000D01*
Y221000D01*
X361500Y219500D01*
Y216000D01*
X355000D01*
X354000Y217000D01*
Y226500D01*
X354500Y227000D01*
X362000D01*
G37*
G36*
G01X370999Y133498D02*
X374371D01*
G03X375800Y132898I1429J1402D01*
G01X380601D01*
X381000Y132500D01*
Y129500D01*
X379000Y127500D01*
X371000D01*
X370500Y128000D01*
Y133000D01*
X370999Y133498D01*
G37*
G36*
G01X367000Y135500D02*
X366750Y135750D01*
Y142000D01*
X367000D01*
Y145000D01*
X367500Y145500D01*
X382500D01*
X384000Y144000D01*
Y136500D01*
X383000Y135500D01*
X367000D01*
G37*
G36*
G01X366000Y225500D02*
X371500D01*
X373000Y224000D01*
Y211500D01*
X372500Y211000D01*
X364000D01*
X363500Y211500D01*
Y213998D01*
X363502D01*
Y214002D01*
X364500Y215000D01*
Y218500D01*
X366000Y220000D01*
Y225500D01*
G37*
G36*
G01X360800Y297100D02*
X371700D01*
X372100Y296700D01*
Y285500D01*
X371200Y284600D01*
X360400D01*
X359900Y285100D01*
Y293537D01*
G03X360502Y295500I-2899J1963D01*
G03X360354Y296506I-3502J-1D01*
G01X360320Y296620D01*
X360800Y297100D01*
G37*
G36*
G01X362263Y312100D02*
X369237D01*
X369700Y311637D01*
Y300500D01*
X369100Y299900D01*
X360200D01*
X359800Y300300D01*
Y309637D01*
X362263Y312100D01*
G37*
G36*
G01X406900Y278500D02*
Y294200D01*
X409600Y296900D01*
X414700D01*
X415400Y296200D01*
Y278100D01*
X414700Y277400D01*
X408000D01*
X406900Y278500D01*
G37*
G36*
G01X418300Y297700D02*
X426100D01*
X427200Y296600D01*
Y277004D01*
G03X425885Y275600I1800J-3004D01*
G01X418800D01*
X417850Y276550D01*
Y287550D01*
X417800Y287600D01*
Y297200D01*
X418300Y297700D01*
G37*
G36*
G01X453000Y398000D02*
X462000D01*
X462498Y397502D01*
Y396254D01*
G03X462198Y395200I1702J-1054D01*
G01Y392800D01*
G03X462496Y391750I2002J1D01*
G03X462198Y390700I1704J-1051D01*
G01Y388500D01*
X452000D01*
X451500Y389000D01*
Y396500D01*
X453000Y398000D01*
G37*
G36*
G01X465000Y397500D02*
X472500D01*
X473500Y396500D01*
Y389000D01*
X473000Y388500D01*
X464802D01*
Y390700D01*
G03X464504Y391750I-2002J-1D01*
G03X464802Y392800I-1704J1051D01*
G01Y395200D01*
G03X464527Y396211I-2002J-2D01*
G01X464500Y396258D01*
Y397000D01*
X465000Y397500D01*
G37*
G36*
G01X492200Y249000D02*
X503000D01*
X503500Y248500D01*
Y240100D01*
X502400Y239000D01*
X492100D01*
X491706Y239394D01*
Y248506D01*
X492200Y249000D01*
G37*
G36*
G01X507100Y251300D02*
X520700D01*
X521300Y250700D01*
Y249923D01*
X521156Y249881D01*
G03Y244119I844J-2881D01*
G01X521300Y244077D01*
Y240100D01*
X520500Y239300D01*
X506900D01*
X506000Y240200D01*
Y250200D01*
X507100Y251300D01*
G37*
G36*
G01X505755Y386498D02*
X506245D01*
X506291Y386471D01*
G03X507300Y386198I1009J1728D01*
G01X509700D01*
G03X509717Y386199I-109J1996D01*
G01X509801D01*
X510000Y386000D01*
Y374000D01*
X509500Y373500D01*
X504000D01*
X502500Y375000D01*
Y386198D01*
X504700D01*
G03X505709Y386471I0J2001D01*
G01X505755Y386498D01*
G37*
G36*
G01X503000Y396500D02*
X509000D01*
X509500Y396000D01*
Y388802D01*
X507300D01*
G03X506289Y388527I2J-2002D01*
G01X506242Y388500D01*
X505758D01*
X505711Y388527D01*
G03X504700Y388802I-1013J-1727D01*
G01X502300D01*
G03X502283Y388801I109J-1996D01*
G01X502199D01*
X502000Y389000D01*
Y395500D01*
X503000Y396500D01*
G37*
G36*
G01X523000Y356500D02*
X538400D01*
X548500Y346400D01*
Y323102D01*
X548498D01*
Y318498D01*
X547500Y317500D01*
X524500D01*
X522400Y319600D01*
Y321400D01*
X522200Y321600D01*
Y355700D01*
X523000Y356500D01*
G37*
G36*
G01X533144Y374850D02*
X543650D01*
X545100Y373400D01*
Y359700D01*
X544300Y358900D01*
X538000D01*
X537500Y359400D01*
Y362500D01*
X535500Y364500D01*
X526500D01*
X525300Y365700D01*
Y374400D01*
X525750Y374850D01*
X527256D01*
X527286Y374841D01*
G03X528200Y374698I915J2859D01*
G03X529114Y374841I-1J3002D01*
G01X529144Y374850D01*
X531256D01*
X531286Y374841D01*
G03X532200Y374698I915J2859D01*
G03X533114Y374841I-1J3002D01*
G01X533144Y374850D01*
G37*
G36*
G01X541256Y161500D02*
X545000D01*
X545500Y161000D01*
Y158000D01*
X545000Y157500D01*
X538500D01*
X538000Y158000D01*
Y161198D01*
X540200D01*
G03X541256Y161500I-1J2002D01*
G37*
G36*
G01X544500Y164500D02*
X544000Y164000D01*
X537000D01*
X536500Y164500D01*
Y180000D01*
X537000Y180500D01*
X544000D01*
X544500Y180000D01*
Y164500D01*
G37*
G36*
G01X537500Y191500D02*
X538000Y192000D01*
X544000D01*
X544500Y191500D01*
Y184500D01*
X544000Y184000D01*
X537500D01*
Y191500D01*
G37*
G36*
G01X554300Y90900D02*
X563700D01*
X565200Y89400D01*
Y82400D01*
X565300Y82300D01*
Y77172D01*
G03Y74828I3299J-1172D01*
G01Y70300D01*
X563500Y68500D01*
X560300D01*
X559300Y69500D01*
Y77500D01*
X558300Y78500D01*
X553800D01*
X553000Y79300D01*
Y89600D01*
X554300Y90900D01*
G37*
G36*
G01X562200Y212800D02*
Y213907D01*
Y216600D01*
X562400Y216800D01*
X566600D01*
X567700D01*
X567900Y216600D01*
Y212700D01*
X567200Y212000D01*
X562600D01*
X562200Y212400D01*
Y212800D01*
G37*
G36*
G01X564400Y209900D02*
X574700D01*
X575850Y208750D01*
Y203950D01*
X575102Y203202D01*
X573400D01*
G03X572889Y203112I1J-1502D01*
G01X572856Y203100D01*
X572030D01*
G03X570600Y203702I-1431J-1400D01*
G01X566800D01*
G03X565370Y203100I1J-2002D01*
G01X564300D01*
X563400Y204000D01*
Y208900D01*
X564400Y209900D01*
G37*
G36*
G01X567900Y220300D02*
Y217800D01*
X567300Y217200D01*
X562400D01*
X562200Y217400D01*
Y221200D01*
X562600Y221600D01*
X566600D01*
X567900Y220300D01*
G37*
G36*
G01X551700Y348300D02*
X562203D01*
G02X562592Y347808I0J-400D01*
G03X562498Y347000I3408J-806D01*
G03X565054Y343628I3502J0D01*
G01X565200Y343587D01*
Y317950D01*
X563400Y316150D01*
X551750D01*
X550600Y317300D01*
Y326298D01*
X550702D01*
Y331302D01*
X550600D01*
Y333898D01*
X550702D01*
Y338902D01*
X550600D01*
Y341598D01*
X550702D01*
Y346602D01*
X550600D01*
Y347200D01*
X551700Y348300D01*
G37*
G36*
G01X573058Y221700D02*
X576200D01*
X576900Y221000D01*
Y214500D01*
X575500Y213100D01*
X569902D01*
Y219451D01*
X569905Y219469D01*
G03X569945Y219798I-2956J526D01*
G03X573058Y221700I-2J3502D01*
G37*
G36*
G01X620551Y90157D02*
X657017D01*
Y54005D01*
X656242Y53230D01*
X620500D01*
Y54134D01*
X620551D01*
Y90157D01*
G37*
G36*
G01Y434492D02*
X656403D01*
X656980Y433915D01*
Y392520D01*
X620551D01*
Y434492D01*
G37*
G36*
G01X655042Y230000D02*
Y234818D01*
G02X650246Y241437I2169J6619D01*
G01Y242711D01*
G02X650862Y243047I400J-1D01*
G03X652087Y242521I2190J3410D01*
G01X652239Y242484D01*
Y241437D01*
G03X657035Y236468I4972J0D01*
G01Y230000D01*
X655042D01*
G37*
G36*
G01X652239Y279276D02*
G03Y276630I813J-1323D01*
G01Y250430D01*
X652087Y250393D01*
G03X650862Y249867I965J-3936D01*
G02X650246Y250203I-216J337D01*
G01Y258958D01*
G03Y263042I-1446J2042D01*
G01Y282678D01*
G02X655042Y289297I6966J0D01*
G01Y392518D01*
X657035D01*
Y287647D01*
G03X652239Y282678I177J-4969D01*
G01Y279276D01*
G37*
G36*
G01X655042Y191500D02*
X657035D01*
Y91943D01*
G02X656550Y91552I-400J0D01*
G03X656039Y91607I-511J-2346D01*
G01X656037D01*
G03X655527Y91552I1J-2402D01*
G02X655042Y91942I-85J391D01*
G01Y191500D01*
G37*
%LPC*%
G75*
G54D58*
X143567Y106043D03*
X146067Y268043D03*
X268567Y112143D03*
Y255943D03*
%LPD*%
G75*
G54D10*
G01X59600Y60200D02*
X60900Y61500D01*
X63500D01*
G01X67700D02*
Y65000D01*
G01X74600Y320000D02*
Y324500D01*
G01Y320000D02*
X87000D01*
X94500Y312500D01*
G01X129000Y321500D02*
X125500Y325000D01*
Y342500D01*
X130000Y347000D01*
Y349664D01*
G01X432000Y91900D02*
X427500D01*
X8878Y21717D03*
X4878D03*
X4000Y25619D03*
Y29619D03*
Y33619D03*
Y37619D03*
Y41619D03*
Y45619D03*
Y49619D03*
Y281619D03*
Y285619D03*
Y289619D03*
Y293619D03*
Y297619D03*
Y301619D03*
Y305619D03*
Y309619D03*
Y313619D03*
Y337619D03*
Y341619D03*
Y345619D03*
Y349619D03*
Y353619D03*
Y357619D03*
Y361619D03*
Y365619D03*
Y369619D03*
Y373619D03*
Y377619D03*
Y381619D03*
Y385619D03*
Y389619D03*
Y393619D03*
Y397619D03*
Y401619D03*
Y405619D03*
Y409619D03*
Y413619D03*
Y417619D03*
Y421619D03*
Y425619D03*
Y429619D03*
X4413Y433598D03*
X8413D03*
X24878Y21717D03*
X20878D03*
X16878D03*
X12878D03*
X12413Y433598D03*
X16413D03*
X20413D03*
X24413D03*
X28413D03*
X44878Y21717D03*
X40878D03*
X36878D03*
X32878D03*
X28878D03*
X32413Y433598D03*
X36413D03*
X40413D03*
X44413D03*
X55055Y25073D03*
X52878Y21717D03*
X48878D03*
X55055Y41073D03*
Y37073D03*
Y33073D03*
Y29073D03*
X61463Y54048D03*
X57859Y52313D03*
X55558Y49041D03*
X55055Y45073D03*
X48413Y433598D03*
X52413D03*
X56413D03*
X60413D03*
X77460Y54197D03*
X73460D03*
X69460D03*
X65460D03*
X79248Y266100D03*
X73600Y252500D03*
X67000Y283100D03*
X68600Y274000D03*
X75500Y282500D03*
X63800Y274000D03*
X76700Y357500D03*
X67100D03*
X73500D03*
X70300D03*
X68413Y433598D03*
X72413D03*
X76413D03*
X80413D03*
X64413D03*
X97460Y54197D03*
X93460D03*
X89460D03*
X85460D03*
X81460D03*
X88300Y163900D03*
X86800Y230000D03*
X85600Y263700D03*
X98000Y420000D03*
X90000Y420500D03*
X85500D03*
X84413Y433598D03*
X88413D03*
X92413D03*
X96413D03*
X113460Y54197D03*
X109460D03*
X105460D03*
X101460D03*
X113700Y382500D03*
X104100D03*
X110500D03*
X107300D03*
X104413Y433598D03*
X108413D03*
X112413D03*
X100413D03*
X132920Y51926D03*
X129450Y53917D03*
X125460Y54197D03*
X121460D03*
X117460D03*
X131500Y290500D03*
X116413Y433598D03*
X120413D03*
X124413D03*
X128413D03*
X132413D03*
X135299Y24509D03*
X150163Y21717D03*
X146163D03*
X142163D03*
X138163D03*
X135299Y28509D03*
Y32509D03*
Y36509D03*
Y40509D03*
Y44509D03*
X134977Y48496D03*
X144000Y62500D03*
X138500Y75000D03*
X145900Y75200D03*
X136000Y290500D03*
X138250Y372250D03*
X140413Y433598D03*
X144413D03*
X148413D03*
X136413D03*
X158163Y21717D03*
X154163D03*
X158795Y25667D03*
Y41667D03*
Y37667D03*
Y33667D03*
Y29667D03*
X160736Y49309D03*
X159112Y45654D03*
X163543Y52159D03*
X151840Y79935D03*
X153500Y390500D03*
X167100Y405600D03*
X152413Y433598D03*
X156413D03*
X160413D03*
X164413D03*
X180341Y47225D03*
X178196Y50601D03*
X168413Y433598D03*
X172413D03*
X176413D03*
X180413D03*
X184413D03*
X191535Y28900D03*
X201950Y29050D03*
X187598Y36900D03*
X189500Y33000D03*
X186000D03*
X187598Y28900D03*
X191535Y41200D03*
X198135Y36500D03*
X200413Y433598D03*
X188413D03*
X192413D03*
X196413D03*
X210500Y30500D03*
X208300Y289500D03*
X217300D03*
X212800D03*
X209660Y331500D03*
X204413Y433598D03*
X208413D03*
X212413D03*
X216413D03*
X220413D03*
X232700Y29100D03*
X221800Y289500D03*
X224500Y302000D03*
X224413Y433598D03*
X228413D03*
X232413D03*
X236413D03*
X254527Y28900D03*
X244619D03*
X254527Y33900D03*
X250222Y76300D03*
X247022D03*
X240508D03*
Y66700D03*
X243822Y76300D03*
X253422D03*
X240508Y69900D03*
Y73100D03*
X240413Y433598D03*
X244413D03*
X248413D03*
X252413D03*
X264339Y35300D03*
Y38500D03*
Y32100D03*
X264304Y28900D03*
X272309D03*
X264339Y41700D03*
X263300Y52200D03*
X269907Y76300D03*
X266707D03*
X263507D03*
X256413Y433598D03*
X260413D03*
X264413D03*
X268413D03*
X272413D03*
X280087Y35300D03*
Y38500D03*
Y41700D03*
Y32100D03*
X280052Y28900D03*
X288057D03*
X285055Y76300D03*
X281855D03*
X288255D03*
X273107D03*
X278655D03*
X284500Y181100D03*
Y184300D03*
Y187500D03*
X283400Y198700D03*
X280200D03*
X277000D03*
X286600D03*
X284500Y190700D03*
X286151Y329500D03*
X289600Y330100D03*
X288413Y433598D03*
X284413D03*
X280413D03*
X276413D03*
X295835Y35300D03*
Y38500D03*
Y41700D03*
Y32100D03*
X295800Y28900D03*
X295835Y44900D03*
Y48100D03*
X298726Y43529D03*
Y49471D03*
X298700Y327000D03*
Y323500D03*
X293200Y329500D03*
X304413Y433598D03*
X300413D03*
X296413D03*
X292413D03*
X307708Y28900D03*
X321402Y54197D03*
X317402D03*
X314763Y85237D03*
X312500Y87500D03*
X310237Y89763D03*
X317025Y82975D03*
X319510Y190299D03*
X322710D03*
X322200Y320500D03*
Y325000D03*
X310600Y330500D03*
Y335000D03*
X322200Y338500D03*
X324413Y433598D03*
X320413D03*
X316413D03*
X312413D03*
X308413D03*
X329402Y54197D03*
X325402D03*
X337402D03*
X341402D03*
X333402D03*
X338599Y108500D03*
X341799D03*
X337500Y113000D03*
Y122600D03*
Y116200D03*
Y119400D03*
X329110Y190299D03*
X325910D03*
X340413Y433598D03*
X336413D03*
X332413D03*
X328413D03*
X345402Y54197D03*
X349402D03*
X353402D03*
X357402D03*
X359300Y92000D03*
X348199Y108500D03*
X348264Y104707D03*
X357864D03*
X344999Y108500D03*
X351464Y104707D03*
X354664D03*
X352300Y175000D03*
X345301Y196299D03*
Y186699D03*
Y193099D03*
Y189899D03*
X354850Y276100D03*
X354800Y285600D03*
Y289800D03*
X355000Y332500D03*
Y328000D03*
X356413Y433598D03*
X352413D03*
X348413D03*
X344413D03*
X369402Y54197D03*
X373402D03*
X377402D03*
X361402D03*
X365402D03*
X373500Y78000D03*
X368900Y92000D03*
X373500Y94000D03*
X365700Y92000D03*
X362500D03*
X365101Y191559D03*
Y188359D03*
Y194759D03*
Y185159D03*
X375500Y350500D03*
X376413Y433598D03*
X372413D03*
X368413D03*
X364413D03*
X360413D03*
X381402Y54197D03*
X385402D03*
X389402D03*
X393402D03*
X380500Y77400D03*
X380400Y81600D03*
X390000Y100500D03*
X387193Y143005D03*
X391130D03*
X387193Y135130D03*
X391130Y139067D03*
X387193D03*
Y146942D03*
X391130D03*
Y135130D03*
X387193Y150879D03*
X391130D03*
X387193Y158753D03*
X391130D03*
X387193Y154816D03*
Y162690D03*
X391130D03*
Y154816D03*
X387193Y166627D03*
X391130D03*
X387193Y170564D03*
X391130Y178437D03*
X387193D03*
X391130Y170564D03*
X383128Y178372D03*
X391130Y182374D03*
Y186311D03*
X385500Y196154D03*
X387193Y186311D03*
X391130Y205996D03*
Y209933D03*
X387193Y217807D03*
X388500Y400000D03*
X393500D03*
X393000Y418500D03*
X392413Y433598D03*
X388413D03*
X384413D03*
X380413D03*
X397402Y54197D03*
X401402D03*
X405402D03*
X409402D03*
X409200Y100500D03*
X398450Y116099D03*
X408050D03*
X401650D03*
X404850D03*
X395067Y146942D03*
X399005D03*
X395067Y139067D03*
X399005D03*
Y143005D03*
X402942D03*
Y146942D03*
X406879D03*
X410816D03*
X395067Y143005D03*
Y131193D03*
X406879Y135130D03*
X410816D03*
X406879Y139067D03*
X402942D03*
X410811Y131188D03*
X406874D03*
X399000Y135125D03*
Y131188D03*
X395067Y135130D03*
X410816Y143005D03*
Y139067D03*
X406879Y143005D03*
X395067Y154816D03*
X399005D03*
X395067Y162690D03*
X399005D03*
X395067Y150879D03*
X402942Y154816D03*
X399005Y158753D03*
X410816D03*
X402942Y162690D03*
X410816D03*
Y150879D03*
Y154816D03*
X395067Y158753D03*
X402942Y150879D03*
X406879D03*
X399005D03*
X402942Y158753D03*
X406879Y162690D03*
Y154816D03*
Y158753D03*
X395067Y170564D03*
X399005D03*
X395067Y166627D03*
X410816D03*
X402942Y170564D03*
X406879D03*
X395067Y178437D03*
X399005D03*
X410816D03*
Y170564D03*
X402942Y166627D03*
X406879D03*
X399005D03*
X402942Y178437D03*
X406879D03*
X395067Y182374D03*
X399005Y186311D03*
Y190248D03*
X406879Y198122D03*
X399005Y182374D03*
X410816Y186311D03*
X395067Y194185D03*
X402942Y190248D03*
X406879Y182374D03*
Y186311D03*
Y194185D03*
X395067Y186311D03*
Y190248D03*
X402942Y182374D03*
X399005Y198122D03*
X395067D03*
X410816Y182374D03*
Y198122D03*
X402942Y186311D03*
Y194185D03*
X399005D03*
X402942Y198122D03*
X410816Y194185D03*
X406879Y190248D03*
X402942Y209933D03*
X395067Y213870D03*
X410816Y205996D03*
X399005Y202059D03*
X395067D03*
X402942Y205996D03*
X399005D03*
X406879Y202059D03*
X410816Y209933D03*
Y202059D03*
X395067Y209933D03*
X406879Y205996D03*
X402942Y202059D03*
X395067Y205996D03*
X406879Y213870D03*
Y217807D03*
X398500Y400000D03*
X403000Y418500D03*
X398000D03*
X408413Y433598D03*
X404413D03*
X400413D03*
X396413D03*
X417402Y54197D03*
X421402D03*
X425402D03*
X429402D03*
X413402D03*
X413622Y75000D03*
X414753Y131193D03*
X422627Y146942D03*
X426564Y135130D03*
X418690Y139067D03*
X422627Y135130D03*
X418690D03*
X414753D03*
X422627Y131193D03*
X418690D03*
X426564Y146942D03*
Y131193D03*
Y139067D03*
X422627D03*
Y143005D03*
X418690D03*
X414753D03*
Y139067D03*
X418690Y146942D03*
X414753D03*
Y162690D03*
Y154816D03*
X418690Y158753D03*
X422627Y162690D03*
Y154816D03*
X426564Y162690D03*
Y158753D03*
X418690Y154816D03*
Y162690D03*
X414753Y158753D03*
X422627D03*
X426564Y154816D03*
X414753Y150879D03*
X422627D03*
X418690D03*
X426564D03*
X418690Y166627D03*
X414753Y170564D03*
X422627D03*
X418690Y178437D03*
X426564Y166627D03*
Y178437D03*
X418690Y170564D03*
X414753Y166627D03*
X426564Y170564D03*
X414753Y178437D03*
X422627Y166627D03*
Y178437D03*
Y190248D03*
X414753Y194185D03*
X426564Y198122D03*
X418690Y182374D03*
X426564Y190248D03*
X418690Y198122D03*
X422627Y194185D03*
Y186311D03*
Y182374D03*
X426564D03*
X414753Y190248D03*
X418690D03*
Y186311D03*
X414753D03*
Y182374D03*
Y198122D03*
X426564Y194185D03*
X422627Y198122D03*
X418690Y194185D03*
X414753Y213870D03*
X418690Y202059D03*
X422627Y209933D03*
X418690Y205996D03*
X414753D03*
Y209933D03*
X418690Y213870D03*
X414753Y202059D03*
X426564D03*
Y205996D03*
Y209933D03*
X422627Y202059D03*
Y205996D03*
X418690Y209933D03*
X426564Y217807D03*
X414000Y419000D03*
X422337Y424000D03*
X416800D03*
X428413Y433598D03*
X424413D03*
X420413D03*
X416413D03*
X412413D03*
X433402Y54197D03*
X437402D03*
X441402D03*
X445402D03*
X444050Y116599D03*
X434450D03*
X437650D03*
X440850D03*
X442311Y139067D03*
X446248Y143005D03*
X434437D03*
X438374Y131193D03*
X446248Y146942D03*
X442311Y143005D03*
Y146942D03*
X438374Y135130D03*
X434437Y146942D03*
X438374D03*
X446248Y139067D03*
X445939Y135439D03*
X438374Y143005D03*
Y139067D03*
X434437D03*
Y135130D03*
Y131193D03*
X446248Y158753D03*
X442311Y162690D03*
X434437D03*
Y154816D03*
X438374Y162690D03*
Y150879D03*
Y158753D03*
X442311Y154816D03*
X434437Y158753D03*
X442311D03*
X438374Y154816D03*
X446248D03*
Y162690D03*
X434437Y150879D03*
X442311D03*
X446248D03*
X438374Y166627D03*
X446248D03*
X434437Y170564D03*
X442311D03*
X446248Y178437D03*
X434437Y166627D03*
X438374Y178437D03*
Y170564D03*
X442311Y166627D03*
X434437Y178437D03*
X446248Y170564D03*
X442311Y178437D03*
X446248Y182374D03*
Y186311D03*
X442311D03*
Y182374D03*
X438374Y194185D03*
Y190248D03*
X446248D03*
X434437Y186311D03*
Y190248D03*
Y194185D03*
Y182374D03*
X438374Y198122D03*
X442311Y190248D03*
Y194185D03*
X434437Y198122D03*
X446248D03*
X438374Y182374D03*
Y186311D03*
X446248Y194185D03*
X442311Y198122D03*
X434437Y205996D03*
X446248Y209933D03*
X438374D03*
Y205996D03*
Y213870D03*
X442311Y202059D03*
X434437D03*
Y213870D03*
X442311Y205996D03*
X446248D03*
Y202059D03*
X434437Y209933D03*
X438374Y217807D03*
X434437D03*
X446500Y289500D03*
X439500Y337892D03*
X442500Y336089D03*
X439500Y341500D03*
X443000Y386500D03*
Y401500D03*
Y396500D03*
X432000D03*
X444000Y416500D03*
X444413Y433598D03*
X440413D03*
X436413D03*
X432413D03*
X449402Y54197D03*
X453402D03*
X457402D03*
X461402D03*
X450930Y122167D03*
X460530D03*
X457330D03*
X454130D03*
X454122Y143005D03*
X457844Y131408D03*
X461996Y131193D03*
X450185Y143005D03*
Y135130D03*
X461996Y139067D03*
X454122D03*
X458059D03*
X461996Y135130D03*
X454122D03*
X457844Y135345D03*
X449876Y131502D03*
X454122Y131193D03*
X458059Y146942D03*
X461996D03*
X450185D03*
X454122D03*
X458059Y143005D03*
X461996D03*
X450185Y139067D03*
X458059Y158753D03*
X450185Y154816D03*
X461996Y158753D03*
X450185Y162690D03*
X454122Y158753D03*
Y162690D03*
X450185Y158753D03*
X458059Y150879D03*
Y162690D03*
X454122Y150879D03*
X461996D03*
X454122Y154816D03*
X458059D03*
X461996D03*
X450185Y150879D03*
X458059Y178437D03*
Y166627D03*
X450185Y170564D03*
X454123D03*
X454122Y166627D03*
X450185D03*
Y178437D03*
X454122D03*
X461996Y170564D03*
Y178437D03*
X458060Y170564D03*
X461996Y166627D03*
X450185Y182374D03*
X454122Y186311D03*
X450185Y198122D03*
X458059Y190248D03*
X454122Y182374D03*
X461996D03*
X458059Y194185D03*
X461996Y186311D03*
X458059Y182374D03*
X454122Y194185D03*
X450185D03*
X454122Y190248D03*
X458059Y186311D03*
X454122Y198122D03*
X458059D03*
X461996Y190248D03*
Y198122D03*
Y194185D03*
X450185Y186311D03*
Y190248D03*
X461996Y202059D03*
X458059Y213870D03*
X454122Y205996D03*
X461996Y209933D03*
Y205996D03*
Y213870D03*
X458059Y202059D03*
Y205996D03*
X454122Y209933D03*
X458059D03*
X450185D03*
Y213870D03*
X454122D03*
X450185Y202059D03*
X454122D03*
X450185Y205996D03*
Y217807D03*
X461996D03*
X458059D03*
X464413Y433598D03*
X460413D03*
X456413D03*
X452413D03*
X448413D03*
X465402Y54197D03*
X469402D03*
X473402D03*
X477402D03*
X481402D03*
X465933Y146942D03*
X469870Y135130D03*
X465933Y131193D03*
X473807Y135130D03*
Y139067D03*
Y146942D03*
X469870D03*
X473807Y143005D03*
X465933Y139067D03*
X469870D03*
Y131193D03*
X473807D03*
X465933Y135130D03*
Y143005D03*
X469870D03*
X465933Y154816D03*
X469870D03*
X465933Y158753D03*
Y150879D03*
X469870D03*
Y178437D03*
X473807Y166627D03*
X465933D03*
Y170564D03*
Y178437D03*
X469870Y166627D03*
Y170564D03*
X473807D03*
Y178437D03*
X465933Y190248D03*
Y194185D03*
X473807Y186311D03*
X469870Y198122D03*
X465933Y186311D03*
X469870Y190248D03*
X473807Y182374D03*
X469870D03*
X465933D03*
X469870Y186311D03*
X473807Y190248D03*
X469870Y194185D03*
X465933Y198122D03*
X473807Y205996D03*
X465933Y209933D03*
X469870Y213870D03*
Y209933D03*
X465933Y205996D03*
X473807Y213870D03*
X469870Y205996D03*
X473807Y209933D03*
X469870Y217807D03*
X473807D03*
X480413Y433598D03*
X476413D03*
X472413D03*
X468413D03*
X485402Y54197D03*
X489402D03*
X493402D03*
X497402D03*
X496413Y433598D03*
X492413D03*
X488413D03*
X484413D03*
X501402Y54197D03*
X505402D03*
X509402D03*
X513402D03*
X516413Y433598D03*
X512413D03*
X508413D03*
X504413D03*
X500413D03*
X517402Y54197D03*
X521402D03*
X525402D03*
X529402D03*
X533402D03*
X533000Y95000D03*
Y99500D03*
X528500Y299000D03*
X532413Y433598D03*
X528413D03*
X524413D03*
X520413D03*
X537402Y54197D03*
X541402D03*
X545402D03*
X549402D03*
X548413Y433598D03*
X544413D03*
X540413D03*
X536413D03*
X553402Y54197D03*
X557402D03*
X561402D03*
X565402D03*
X566600Y212900D03*
X552000Y367597D03*
Y371141D03*
X555200Y367597D03*
Y371141D03*
X552000Y374684D03*
Y378227D03*
X555200D03*
Y374684D03*
X568413Y433598D03*
X564413D03*
X560413D03*
X556413D03*
X552413D03*
X569402Y54197D03*
X573402D03*
X577402D03*
X581402D03*
X585402D03*
X584413Y433598D03*
X580413D03*
X576413D03*
X572413D03*
X589402Y54197D03*
X593402D03*
X597402D03*
X601402D03*
X600413Y433598D03*
X596413D03*
X592413D03*
X588413D03*
X605402Y54197D03*
X609402D03*
X613402D03*
X617402D03*
X621402D03*
X619961Y230874D03*
Y221274D03*
Y224474D03*
Y227674D03*
X620413Y433598D03*
X616413D03*
X612413D03*
X608413D03*
X604413D03*
X625402Y54197D03*
X629402D03*
X625800Y215874D03*
X636413Y433598D03*
X632413D03*
X628413D03*
X624413D03*
X649402Y54197D03*
X653402D03*
X656039Y57205D03*
Y61205D03*
Y65205D03*
Y69205D03*
Y73205D03*
Y77205D03*
Y81205D03*
Y85205D03*
Y89205D03*
Y93205D03*
Y97205D03*
Y101205D03*
Y105205D03*
Y109205D03*
Y113205D03*
Y117205D03*
Y121205D03*
Y125205D03*
Y129205D03*
Y145205D03*
Y133205D03*
Y137205D03*
Y141205D03*
Y149205D03*
Y153205D03*
Y157205D03*
Y161205D03*
Y165205D03*
Y169205D03*
Y173205D03*
Y177205D03*
Y181205D03*
Y235585D03*
Y311909D03*
Y315909D03*
Y319909D03*
Y323909D03*
Y327909D03*
Y331909D03*
Y335909D03*
Y339909D03*
Y343909D03*
Y347909D03*
Y351909D03*
Y355909D03*
Y359909D03*
Y363909D03*
Y367909D03*
Y371909D03*
Y375909D03*
Y379909D03*
Y383909D03*
Y387909D03*
Y391909D03*
Y395909D03*
Y399909D03*
Y403909D03*
Y407909D03*
Y411909D03*
Y415909D03*
Y419909D03*
Y423909D03*
Y427909D03*
Y431909D03*
X652413Y433598D03*
X648413D03*
X644413D03*
X640413D03*
G54D20*
X36950Y302840D03*
Y295160D03*
Y297720D03*
Y300280D03*
X55050Y295160D03*
Y302840D03*
Y300280D03*
Y297720D03*
G54D11*
X6039Y61260D03*
Y81260D03*
Y118346D03*
Y138346D03*
Y175433D03*
Y195433D03*
Y232520D03*
Y252520D03*
X26039Y61260D03*
Y81260D03*
Y118346D03*
Y138346D03*
Y175433D03*
Y195433D03*
Y232520D03*
Y252520D03*
X143567Y106043D03*
X146067Y268043D03*
X268567Y112143D03*
Y255943D03*
G54D30*
X246559Y228700D03*
X241441Y219300D03*
Y228700D03*
X244000Y219300D03*
X246559D03*
G54D21*
X95000Y84500D03*
X110500Y414500D03*
X578000Y116500D03*
G54D12*
X11264Y152264D03*
X17500Y91000D03*
X12500Y96000D03*
X19100Y148798D03*
X23600D03*
X28100D03*
X17000Y204500D03*
X12500Y209500D03*
X11963Y266437D03*
X28700Y262508D03*
X19900Y283000D03*
X16000Y302500D03*
Y297500D03*
Y307500D03*
X24100Y310900D03*
X18000Y314500D03*
X11976Y323524D03*
X45500Y126000D03*
X41500Y127500D03*
X41409Y132591D03*
X45500Y161000D03*
X41600Y148798D03*
X32600Y148700D03*
X37100Y148798D03*
X45000Y213000D03*
X42000Y236800D03*
X37400Y282900D03*
X43000Y314500D03*
X33000D03*
X39500Y309000D03*
X34500D03*
X59600Y60200D03*
X51772Y73600D03*
X47600Y68900D03*
X60100Y73000D03*
X47000Y100000D03*
X61400Y104900D03*
X50500Y104800D03*
X62500Y100500D03*
Y117000D03*
X48390Y128312D03*
X51772Y130500D03*
X46500Y133000D03*
X53900Y157000D03*
X60600Y161200D03*
X60500Y152000D03*
X51400Y161600D03*
X51772Y187987D03*
X58000Y213500D03*
X54000D03*
X63000Y206000D03*
Y210500D03*
Y215000D03*
X57500Y218500D03*
X51452Y219900D03*
X51772Y245074D03*
X54590Y266870D03*
X48232Y264530D03*
X48500Y271500D03*
X52500Y278000D03*
X62000Y307000D03*
X61489Y332329D03*
X62000Y323500D03*
X63500Y359600D03*
X62500Y365000D03*
Y369000D03*
Y382000D03*
X60300Y401100D03*
Y413100D03*
X67700Y65000D03*
X66400Y77400D03*
X66000Y91100D03*
X76400Y87200D03*
X76321Y78300D03*
X78500Y82250D03*
X69500Y100000D03*
X67500Y114500D03*
X68000Y119000D03*
X73500D03*
X69500Y130000D03*
X74000D03*
X75000Y141700D03*
X64445Y168945D03*
X69000Y187500D03*
Y193000D03*
X69023Y198524D03*
X74593Y202207D03*
X71400Y221700D03*
X67500Y222900D03*
X67400Y227100D03*
X71400Y232900D03*
X71500Y247800D03*
X68000Y235500D03*
X67700Y240200D03*
X80148Y253648D03*
X64248Y258000D03*
X64500Y296750D03*
X78000Y291500D03*
X66000Y318500D03*
X72000Y335000D03*
X66000Y323500D03*
X79500Y341790D03*
X72000Y346300D03*
X73000Y365000D03*
X69500D03*
X66000D03*
X66500Y382000D03*
X70500D03*
X80700Y399200D03*
Y404200D03*
X71300D03*
Y399200D03*
X76000D03*
Y404200D03*
X71300Y394200D03*
X76000D03*
X80700D03*
X64300Y407600D03*
Y395600D03*
X66000Y419000D03*
X80700Y409200D03*
X76000D03*
X71300D03*
X88900Y67000D03*
X86000Y63100D03*
X83300Y87100D03*
X82100Y79300D03*
X96500Y98000D03*
X92250Y97750D03*
X94500Y105000D03*
X89000Y110500D03*
X90500Y105000D03*
X87000Y130000D03*
Y120000D03*
X86600Y141300D03*
X90500Y144500D03*
X96500Y140000D03*
X91500D03*
X88400Y154900D03*
X93900Y155200D03*
X94500Y163000D03*
X88250Y177250D03*
X83500Y178000D03*
X97500Y172000D03*
X95500Y192000D03*
X83500Y193000D03*
Y188500D03*
X85750Y202750D03*
X97500Y214000D03*
X93032Y246477D03*
X96000Y241000D03*
X85700Y236500D03*
X87200Y258300D03*
X98500Y256661D03*
X86900Y267200D03*
X95900Y278900D03*
X94500Y312500D03*
X95000Y321500D03*
X95593Y333347D03*
X82500Y339000D03*
X97500Y341000D03*
X95000Y344500D03*
X82800Y364600D03*
X94500Y373000D03*
Y369000D03*
Y364500D03*
X90500D03*
X86500D03*
X91500Y359500D03*
X83500Y360000D03*
X82800Y384600D03*
X94000Y384500D03*
X90500D03*
X86500D03*
X94500Y376500D03*
X85400Y404200D03*
Y399200D03*
Y394200D03*
X92800Y408100D03*
X96800Y402100D03*
Y396100D03*
X92800D03*
X94000Y420000D03*
X83000Y417000D03*
X85400Y409200D03*
X96800Y414100D03*
X111330Y59810D03*
X103800Y76240D03*
X99000Y175500D03*
Y188500D03*
Y197500D03*
Y206500D03*
Y201500D03*
Y260025D03*
X98800Y272400D03*
X112500Y290000D03*
X102500D03*
Y302000D03*
X104500Y305500D03*
X115253Y306247D03*
X99000Y350000D03*
X101500Y341000D03*
X104019Y347425D03*
X113000Y344500D03*
X103000Y364000D03*
X106500D03*
X110000D03*
X115500Y389000D03*
X104500Y377000D03*
X102500Y420000D03*
X119500Y57694D03*
X125000Y76500D03*
X127500Y290500D03*
X117500Y290000D03*
X125095Y306095D03*
X129000Y321500D03*
X123500Y347500D03*
X130000Y349664D03*
X120000Y364500D03*
X129000Y365000D03*
Y370500D03*
X120000Y368000D03*
Y371500D03*
X132000Y379000D03*
X118500D03*
X132000Y375500D03*
X127000Y397061D03*
X117000Y397000D03*
X121169Y396892D03*
X145000Y296500D03*
X141000Y298500D03*
X140100Y306900D03*
X135000Y312000D03*
X149500Y311034D03*
X140700Y320000D03*
X142130Y325630D03*
X146000Y334000D03*
X141916Y333916D03*
X140900Y355400D03*
X142000Y350000D03*
X148000Y370000D03*
X137000Y364000D03*
X140123Y391604D03*
X135500Y383000D03*
Y390500D03*
X141000Y379500D03*
X148500Y380000D03*
X145000Y378000D03*
X140100Y395600D03*
X135500Y396000D03*
X140000Y401000D03*
X135100Y412600D03*
X143500Y418000D03*
X153270Y58400D03*
X151200Y75191D03*
X160500Y75500D03*
Y71500D03*
X165000Y294000D03*
X166150Y304050D03*
X156000Y316500D03*
X166700Y338800D03*
X151000Y324200D03*
X156000Y325000D03*
Y329000D03*
X159100Y350400D03*
Y354600D03*
X166700Y343800D03*
X151500Y370000D03*
Y358000D03*
X159100Y382600D03*
X163600Y378600D03*
X158500Y405200D03*
X160582Y410000D03*
X160550Y413400D03*
X168500Y294000D03*
X169850Y298950D03*
X182600Y289500D03*
X178600Y378600D03*
Y374600D03*
X175100Y387100D03*
X174600Y401600D03*
Y406100D03*
X175000Y394500D03*
X176000Y416000D03*
X188900Y54960D03*
X192160Y77840D03*
X190000Y301500D03*
Y305500D03*
X189500Y319000D03*
X189000Y326000D03*
X195900Y332500D03*
X191500Y413000D03*
X213500Y54000D03*
X208160Y73990D03*
X215000Y69000D03*
X220000D03*
X204770Y67780D03*
X207800Y83010D03*
X219200Y338800D03*
X219000Y348800D03*
X218000Y381100D03*
X219000Y392500D03*
X215500D03*
X216500Y396000D03*
X220000D03*
X217600Y415100D03*
X223500Y58250D03*
X231000Y68000D03*
Y71500D03*
X228500Y75500D03*
Y79000D03*
X226500Y334000D03*
X222500Y324500D03*
X238000Y345000D03*
X225500Y347500D03*
X230000D03*
X221500Y378500D03*
X226000D03*
X221500Y415000D03*
X225600Y415100D03*
X229500Y415000D03*
X254000Y213500D03*
X241441Y215000D03*
X241900Y238800D03*
X249000Y290300D03*
X247000Y344500D03*
X251000D03*
X255000D03*
X272330Y54871D03*
X259500Y54700D03*
Y70100D03*
X271000Y184500D03*
X269000Y215000D03*
X259000Y223000D03*
Y344500D03*
X282200Y179121D03*
X275260Y223000D03*
X280500Y224300D03*
X288000Y293000D03*
X288500Y317000D03*
X303500Y69400D03*
X296400Y70200D03*
X307500Y160500D03*
X303500Y164000D03*
X298284Y175184D03*
X298500Y184500D03*
X300995Y187611D03*
X297772Y188694D03*
X292000Y294720D03*
X299500Y295500D03*
X301000Y312000D03*
Y317000D03*
X309000Y164500D03*
X311000Y193500D03*
X308967Y204000D03*
X312000Y234400D03*
X324000Y220750D03*
X312500Y225400D03*
X311900Y243400D03*
X311600Y252400D03*
X312000Y269000D03*
Y256500D03*
Y264500D03*
X314500Y276500D03*
X312000Y295500D03*
X317500D03*
X321000D03*
X324500D03*
X310500Y321000D03*
X312500Y307500D03*
X310600Y326000D03*
X321899Y343000D03*
X325000Y363000D03*
X320000Y398500D03*
X324800Y415200D03*
X321300Y416700D03*
X324800Y410700D03*
X336000Y61060D03*
X340500Y63500D03*
Y87000D03*
X338000Y102500D03*
X341500Y233500D03*
X327923Y221577D03*
X335153Y217875D03*
X340953Y237000D03*
X333500Y258900D03*
X339500Y282000D03*
X330500Y291500D03*
X341000Y304000D03*
X332500Y306500D03*
X328000D03*
X338000Y315000D03*
X341400Y323500D03*
X326000Y374000D03*
X340500Y361300D03*
X332500D03*
X325300Y387200D03*
X331500Y376000D03*
X338500D03*
X342000D03*
X339200Y380300D03*
X339300Y384000D03*
Y387700D03*
X340500Y391600D03*
X325300Y396200D03*
Y391700D03*
X336300Y415200D03*
Y419200D03*
X340800Y415200D03*
X349500Y61000D03*
X354500Y60920D03*
X345500Y87000D03*
X354000Y82500D03*
Y128000D03*
X351000Y130500D03*
X353500D03*
X356000D03*
X347500Y141500D03*
X350000D03*
X352500D03*
X355000D03*
X357000Y154200D03*
X353482Y154157D03*
X350085Y154300D03*
X350100Y169400D03*
X352600D03*
X357600D03*
X355100D03*
X347300Y179000D03*
X346500Y174000D03*
X344500Y181500D03*
X351200Y196600D03*
X349128Y186628D03*
X350500Y229500D03*
X355500Y218000D03*
Y220500D03*
Y225500D03*
Y223000D03*
X351000Y233243D03*
X355000Y242500D03*
X354975Y247900D03*
X351000Y237000D03*
X343500Y258900D03*
X352500Y260000D03*
X348500D03*
X357680Y271780D03*
X349000Y303000D03*
Y295500D03*
X355500Y306500D03*
X355000Y337000D03*
X348418Y361300D03*
X344500D03*
X360000Y402400D03*
X359800Y397700D03*
X348279Y405678D03*
X353000Y416500D03*
X350000Y419500D03*
X349500Y415000D03*
X346000Y416000D03*
X376838Y100230D03*
X369310Y109500D03*
X369172Y102828D03*
X367000Y126000D03*
X374300Y129000D03*
X371800D03*
X362000Y123500D03*
Y128000D03*
X374300Y132000D03*
X371800D03*
X376500Y141000D03*
X374000D03*
X360500Y154500D03*
X374900Y154228D03*
X371400Y154300D03*
X367900Y154228D03*
X363600Y176600D03*
X367600Y169300D03*
X364700Y169400D03*
X367400Y174400D03*
X373649Y185735D03*
X369560Y213000D03*
X372060D03*
X367000D03*
X364500D03*
X372500Y232000D03*
X377500Y218500D03*
Y221000D03*
Y223500D03*
X360500Y243000D03*
X367000Y241243D03*
X373500Y247000D03*
X369500Y267500D03*
X375800Y255200D03*
X365000Y268000D03*
X362300Y286100D03*
X365800D03*
X370000Y276000D03*
X374500D03*
X374800Y291100D03*
X370300D03*
X361500Y296100D03*
X365800Y291100D03*
X362100Y291000D03*
X361400Y301500D03*
Y305800D03*
Y309900D03*
X365500Y305900D03*
X375500Y309200D03*
X371000Y326000D03*
X370000Y337000D03*
X366000Y350850D03*
X360700Y406200D03*
X363100Y418300D03*
X360311Y409880D03*
X363100Y422800D03*
X364500Y413500D03*
X384000Y102980D03*
Y109500D03*
X379000Y141000D03*
X378400Y154300D03*
X379800Y177100D03*
X380000Y204500D03*
X379500Y237500D03*
X391900Y246800D03*
X386000D03*
X380100D03*
X386000Y259250D03*
X378000Y273500D03*
Y281000D03*
X382200D03*
X388650Y292650D03*
X378000Y293200D03*
X383000D03*
X393300Y312500D03*
X383000Y341500D03*
X384300Y368700D03*
X383900Y372600D03*
X381000Y365000D03*
X386500D03*
X389500Y370000D03*
X383900Y384600D03*
X379500Y417500D03*
X407000Y120000D03*
X399500D03*
X399000Y221407D03*
Y225000D03*
X407500D03*
X397800Y246800D03*
X403700D03*
X409300D03*
X397800Y259300D03*
X403700D03*
X400000Y265500D03*
X399800Y278400D03*
X409100Y281300D03*
X409300Y286300D03*
X402000Y303000D03*
X409200Y291700D03*
X407500Y300500D03*
X402500Y308000D03*
X397500Y312900D03*
X407500Y305000D03*
X397300Y320700D03*
X408500Y316500D03*
X398000Y336500D03*
Y352000D03*
X411840Y353620D03*
X410000Y358543D03*
X409650Y403950D03*
X412350Y401250D03*
Y397150D03*
X409650Y394450D03*
X422000Y77500D03*
X423000Y72950D03*
X417500Y75000D03*
X413500Y88500D03*
X423000Y100500D03*
X427800Y100300D03*
X429400Y107500D03*
X420900Y246800D03*
X415000D03*
X420900Y259000D03*
X413000Y300500D03*
X417500Y337000D03*
Y352000D03*
X428500Y346000D03*
X413500Y373500D03*
X419000D03*
X425000Y381000D03*
X420500D03*
X419150Y394450D03*
X416450Y401250D03*
Y397150D03*
X419150Y403950D03*
X423500Y415500D03*
X434500Y77000D03*
X433500Y100500D03*
X444200D03*
X431000Y116500D03*
X444000Y226000D03*
X436500Y233000D03*
X444000Y250000D03*
X439500D03*
X435000Y250500D03*
X439500Y266500D03*
X444000Y263000D03*
X440000Y278500D03*
X434600Y278300D03*
X435500Y274500D03*
X445600Y278300D03*
X438150Y283800D03*
X433050Y291400D03*
X439000Y302000D03*
X434500D03*
X433000Y314320D03*
X435143Y306643D03*
X434000Y328000D03*
X447200Y347500D03*
X433000Y353500D03*
X446000Y374500D03*
X438400Y382400D03*
X431000Y416000D03*
X460000Y76000D03*
X448430Y89540D03*
X463500Y86500D03*
Y92000D03*
X450000Y108200D03*
X454600Y108500D03*
X448500Y100500D03*
X462500Y117000D03*
X462000Y224500D03*
X461000Y234500D03*
X457500Y227500D03*
Y223500D03*
X462000Y250000D03*
X457500D03*
X448500D03*
X457500Y237400D03*
X453000Y250000D03*
X457000Y258500D03*
X459500Y262000D03*
X461500Y268409D03*
X460000Y284500D03*
Y289500D03*
X460800Y294200D03*
X461000Y302500D03*
X464500Y298500D03*
X456500Y305500D03*
X461500Y311000D03*
X451000Y306500D03*
X459500Y322000D03*
X459000Y326000D03*
X450900Y330900D03*
X450500Y368500D03*
X453500Y381500D03*
X454000Y393500D03*
Y397000D03*
X450000Y407000D03*
X481000Y70700D03*
X478000Y78000D03*
X465500Y78500D03*
X479867Y138867D03*
X481500Y182016D03*
X477500Y170500D03*
X478000Y198000D03*
X471000Y239000D03*
X477000D03*
X477500Y259000D03*
X468500Y264500D03*
Y270000D03*
X471000Y347000D03*
X481000Y341000D03*
X471400Y363300D03*
X470500Y391000D03*
X493700Y79161D03*
X496000Y85000D03*
X489400Y126300D03*
X493300Y121500D03*
X496000Y163000D03*
Y167500D03*
Y179258D03*
X485033Y174934D03*
X496500Y192500D03*
Y197500D03*
X497500Y214000D03*
X496000Y205500D03*
X485000Y202739D03*
X490500Y216750D03*
X497500Y226000D03*
X497100Y244700D03*
X497200Y240600D03*
X492300Y240800D03*
X492500Y272200D03*
X491800Y277700D03*
X495000Y346000D03*
X488500D03*
X504000Y64500D03*
X508500D03*
X513200Y66000D03*
X508000Y105500D03*
Y110500D03*
Y115500D03*
X503860Y124150D03*
X503900Y128690D03*
X503950Y143000D03*
Y133500D03*
X514500Y151000D03*
Y148000D03*
Y154000D03*
Y157000D03*
X501500Y192500D03*
X507000D03*
Y188500D03*
X515500Y201000D03*
X513000Y210500D03*
X511500Y206500D03*
X513500Y215500D03*
X509000D03*
X512100Y249500D03*
X507100Y240700D03*
X512100D03*
Y244700D03*
X502200Y240700D03*
X512100Y262500D03*
X512300Y254400D03*
X512200Y258700D03*
X512650Y268150D03*
X511900Y276200D03*
X508950Y273250D03*
X506100Y280600D03*
X509000Y340500D03*
X504500D03*
X514000Y374000D03*
X505000Y379500D03*
X504500Y376000D03*
X507500Y394500D03*
X526500Y67500D03*
X533000Y87000D03*
Y82000D03*
X524900Y99000D03*
X522500Y114500D03*
X533500Y124500D03*
X534000Y160500D03*
X517000Y212500D03*
X529800Y223000D03*
X528710Y227500D03*
X534000Y231500D03*
X525400Y247000D03*
X522000D03*
X530350Y257480D03*
X524300Y261700D03*
X523900Y257100D03*
X532500Y272500D03*
X523600Y281100D03*
X531000Y285500D03*
X526000Y295500D03*
X532900Y318900D03*
X527600D03*
X519000Y307500D03*
X532400Y340600D03*
Y345600D03*
X527100Y340600D03*
Y345600D03*
X517500Y374000D03*
X532200Y377700D03*
X523700Y384100D03*
X528200Y377700D03*
X523700D03*
X518000Y382500D03*
X532100Y399000D03*
X527500Y393100D03*
X525176Y411925D03*
X522100Y416500D03*
X551500Y59597D03*
X543957Y60543D03*
X537000Y69000D03*
X549000Y78223D03*
X544300Y87100D03*
X549400Y81600D03*
X534500Y130000D03*
Y136500D03*
X534600Y148300D03*
Y152000D03*
X544000Y159000D03*
X543520Y174970D03*
X542270Y169900D03*
X539770Y174900D03*
Y169900D03*
Y172400D03*
X542270D03*
X542500Y189500D03*
X538500D03*
X540900Y201500D03*
X543500Y205000D03*
X536900Y201500D03*
X545800Y216500D03*
X537500Y232000D03*
X546500Y240500D03*
X549000Y267500D03*
X551700Y256300D03*
X541000Y281500D03*
X541346Y303507D03*
X542000Y296450D03*
X537500Y304000D03*
X538600Y318900D03*
X538100Y340600D03*
Y345600D03*
X539000Y370000D03*
X539300Y365100D03*
X539000Y360000D03*
X543000Y370000D03*
X543300Y365100D03*
X538500Y407875D03*
X543000Y396700D03*
X562500Y74600D03*
X560650Y70450D03*
X559941Y62120D03*
X563341Y62102D03*
X564350Y65350D03*
X559000Y85000D03*
X560200Y81500D03*
X559000Y88800D03*
X565933Y102000D03*
X562533Y102001D03*
X553000Y108500D03*
X568700Y204300D03*
X564700Y204400D03*
X554600Y202400D03*
X566950Y220000D03*
X553800Y240200D03*
X560000Y240000D03*
X565400Y244700D03*
X562000Y254870D03*
X554400Y267500D03*
X556700Y320300D03*
X562500Y336100D03*
X562000Y331600D03*
X564500Y379000D03*
X560200Y386500D03*
X567500Y403000D03*
X555000Y402000D03*
X580500Y65800D03*
X580643Y60900D03*
X585900Y79600D03*
X576459Y161971D03*
X575072Y165500D03*
X580500Y194500D03*
X583000Y192000D03*
X573200Y204300D03*
X586500Y230000D03*
X571000Y217900D03*
X585000Y226500D03*
X578900Y236600D03*
X581500Y267000D03*
X581400Y292250D03*
X583000Y297000D03*
X580300Y356700D03*
X576300Y371200D03*
X580200Y361700D03*
X580100Y366700D03*
X580300Y380700D03*
Y375700D03*
Y385700D03*
Y390700D03*
X576900Y403100D03*
X584000Y421900D03*
X599000Y92500D03*
X588000Y96500D03*
X592000Y127063D03*
X599500Y116500D03*
X597703Y187000D03*
X594003D03*
X601550Y208450D03*
X596450Y210350D03*
X590650Y245680D03*
X604000Y398000D03*
X597500Y421900D03*
X616500Y194874D03*
X610500Y190500D03*
X614100Y224100D03*
X610500Y227000D03*
X614100Y236400D03*
X618650Y249300D03*
X614500Y398000D03*
X637900Y116900D03*
X622000Y127063D03*
Y136000D03*
X633500Y196874D03*
X628500Y189500D03*
X636000Y216142D03*
X627500Y205374D03*
X626989Y237989D03*
X633500Y301500D03*
X647000Y108000D03*
Y113500D03*
G54D31*
X255906Y309646D03*
Y412008D03*
X494094Y309646D03*
Y412008D03*
G54D40*
X567550Y263750D03*
Y272450D03*
X567050Y300950D03*
Y292250D03*
X575050Y272450D03*
X574550Y300950D03*
G54D22*
X109000Y351200D03*
Y345800D03*
X132000Y354800D03*
Y360200D03*
X226000Y67700D03*
Y62300D03*
X284500Y216800D03*
Y222200D03*
X318500Y285300D03*
Y290700D03*
X377000Y86300D03*
Y91700D03*
X427000Y77800D03*
Y83200D03*
X570000Y231800D03*
Y237200D03*
G54D13*
X9000Y279000D03*
Y286000D03*
X12500Y91000D03*
Y101000D03*
Y106000D03*
X13620Y148720D03*
X13000Y157000D03*
X12500Y162000D03*
Y204500D03*
Y214500D03*
Y219500D03*
X19000Y262500D03*
X24200Y262508D03*
X12500Y261500D03*
X15000Y279000D03*
X28700Y274300D03*
X13000Y273327D03*
X28500Y302000D03*
X28000Y296500D03*
X13000Y318700D03*
X28000Y327000D03*
X44500Y73500D03*
X46000Y82000D03*
X45500Y104390D03*
Y182500D03*
X46000Y219500D03*
X40500Y262000D03*
X33200Y262508D03*
X43000Y255500D03*
X29000Y291500D03*
X44500Y309000D03*
X35500Y327000D03*
X55500Y59000D03*
X50500Y60228D03*
X63500Y84500D03*
X57000Y83500D03*
X51500D03*
X59000Y96500D03*
X51765Y96600D03*
X57500Y101500D03*
X56500Y113000D03*
X53740Y126000D03*
X55922Y140543D03*
X47500Y140500D03*
X54130Y152500D03*
X60600Y157000D03*
X48957Y153619D03*
X54500Y171000D03*
X62000Y199500D03*
X53500Y183500D03*
X48000Y200500D03*
X53000D03*
X49600Y213455D03*
X57500Y226500D03*
X53200Y240187D03*
X48500Y252500D03*
X55200Y253500D03*
X52800Y272000D03*
X63600Y291500D03*
X57500Y289000D03*
X61800Y302500D03*
X55000Y336000D03*
Y355400D03*
X62500Y373000D03*
Y378000D03*
X60300Y407100D03*
Y395100D03*
X75500Y62000D03*
X64400Y70000D03*
X71500Y77000D03*
X73500Y112500D03*
X67000Y109000D03*
X79000Y100500D03*
X74000D03*
X64500Y129500D03*
X76100Y154400D03*
X75950Y164200D03*
X79500Y234500D03*
X64700Y251700D03*
X79600Y248900D03*
X72400Y264600D03*
X69500Y257800D03*
X77964Y260100D03*
X75800Y274300D03*
X72000Y271400D03*
X79500Y308500D03*
X79000Y315500D03*
X71000Y330500D03*
X78000D03*
X78635Y324492D03*
X79500Y348500D03*
X64300Y401600D03*
X80500Y420500D03*
X70500Y419000D03*
X75580Y419004D03*
X64300Y413600D03*
X84200Y75000D03*
X93500Y110500D03*
X84000Y100500D03*
X93500Y125000D03*
X87000Y125500D03*
X93500Y130000D03*
X95500Y145500D03*
X95200Y151000D03*
X88500Y149000D03*
X98500Y159000D03*
X91000Y181500D03*
X98500Y165500D03*
X92000Y173000D03*
X83500D03*
X90500Y188500D03*
X94500Y197000D03*
X90500Y193500D03*
X84500Y218000D03*
X95700Y227500D03*
X98500Y218500D03*
X82500Y230500D03*
X84600Y248900D03*
X96500Y235500D03*
X89600Y248900D03*
X98700Y268300D03*
X83200Y260300D03*
X82500Y273200D03*
X87100Y271300D03*
X94500Y299000D03*
X88500Y303000D03*
X95000Y291500D03*
X87500Y295500D03*
X85800Y287452D03*
X82951Y327940D03*
X95100Y351900D03*
X83000Y352500D03*
Y344500D03*
X94500Y380500D03*
X97800Y391800D03*
X96800Y408100D03*
X92800Y402100D03*
Y414100D03*
X112800Y66600D03*
X112880Y73020D03*
X100500Y284730D03*
X112500Y302000D03*
X107500D03*
X105410Y318500D03*
X103000Y351500D03*
X114000Y352000D03*
X99500Y370000D03*
X126000Y67000D03*
Y62000D03*
Y72000D03*
Y318000D03*
X129500Y328000D03*
X119000Y352000D03*
X124500D03*
X148500Y62500D03*
X139500D03*
X150860Y67400D03*
X142070Y77900D03*
X142000Y69535D03*
X145000Y359000D03*
X148500Y376000D03*
X138500Y387500D03*
X135200Y408400D03*
X156800Y301100D03*
X156600Y295000D03*
X153500Y310500D03*
X156000Y320500D03*
X153900Y382200D03*
X163300Y382900D03*
X157900Y387400D03*
X151100Y386300D03*
X167800Y392700D03*
X152100Y399300D03*
X151530Y406300D03*
X153150Y394590D03*
X160600Y417400D03*
X152200Y416300D03*
X151700Y411300D03*
X183170Y56390D03*
X180620Y77890D03*
X180390Y70720D03*
X173170Y70840D03*
X180910Y63390D03*
X179500Y294600D03*
X176500Y290000D03*
X178000Y309500D03*
X173800Y324100D03*
X175100Y382600D03*
X177000Y398000D03*
X174600Y410600D03*
X201370Y43000D03*
X192400Y45786D03*
X198000Y49500D03*
X195000Y54550D03*
X203000Y75000D03*
X196497Y76502D03*
X201700Y327900D03*
X208295Y52500D03*
X207880Y78740D03*
X214810Y78810D03*
X218500Y301700D03*
X213500D03*
X208500D03*
X205000Y337500D03*
Y348800D03*
Y353800D03*
X215000Y343800D03*
X229582Y48918D03*
X222000Y330000D03*
X228500Y382500D03*
X225000Y396000D03*
X243500Y48650D03*
X252700Y44000D03*
X249499Y204000D03*
X255400Y290100D03*
X266500Y206500D03*
X264500Y214000D03*
X287500Y203500D03*
X307300Y61300D03*
X306500Y169500D03*
X295000Y213000D03*
X292500Y222850D03*
X297000Y310500D03*
X293700Y317300D03*
X297700Y335100D03*
X312500Y160500D03*
X320500Y170000D03*
X312000Y217000D03*
X324000Y227500D03*
X311900Y229900D03*
X324000Y236000D03*
X323500Y263000D03*
X318000Y268500D03*
X324300Y254700D03*
X324000Y301000D03*
X323000Y401500D03*
X321300Y423600D03*
X338500Y213500D03*
X332550Y213550D03*
X327500Y232000D03*
X332600Y246600D03*
X328500Y238645D03*
X327800Y246800D03*
X330500Y265000D03*
X337500D03*
X328500Y258900D03*
X338500Y259000D03*
X334350Y282000D03*
X332000Y301500D03*
X336500Y295000D03*
X336525Y320500D03*
Y325500D03*
X341500Y338500D03*
Y328500D03*
Y333500D03*
X336525Y330500D03*
X337000Y344000D03*
X336500Y361300D03*
X330000Y411300D03*
X336300Y423200D03*
X349000Y82500D03*
X344000Y103000D03*
X358400Y182700D03*
X344000Y212000D03*
X345930Y217000D03*
X342900Y246800D03*
X358000Y261500D03*
X344500Y265000D03*
X357000Y295500D03*
X356000Y302300D03*
X344000Y295000D03*
X346000Y306500D03*
X351000Y308000D03*
X358250Y340050D03*
X347700Y381600D03*
X347000Y391200D03*
X347600Y398800D03*
X343700Y409900D03*
X348863Y410500D03*
X370500Y84000D03*
X374600Y178200D03*
X375000Y210000D03*
X367000Y232000D03*
X377500Y226500D03*
X365500Y246500D03*
X376500Y269000D03*
X365500Y279500D03*
X370000Y332500D03*
X361124Y349876D03*
X369000Y413500D03*
X374500Y418500D03*
X379500Y72500D03*
X381700Y92400D03*
X382286Y86214D03*
X382000Y142000D03*
X380000Y210000D03*
X387193Y209933D03*
X384091Y200091D03*
X394000Y223500D03*
X383000Y232500D03*
X390000D03*
X389400Y281100D03*
X394800Y281300D03*
X391600Y304800D03*
X379300Y305000D03*
X383000Y328500D03*
Y333500D03*
Y323500D03*
X390000Y338500D03*
X392500Y329100D03*
Y323900D03*
X383000Y346600D03*
X395000Y370000D03*
Y360000D03*
Y382000D03*
X388500Y391000D03*
X393500D03*
X379500Y381000D03*
Y375800D03*
X396400Y100500D03*
X410816Y190248D03*
X399005Y209933D03*
X406879D03*
X396981Y304482D03*
X408500Y321998D03*
Y311000D03*
X408000Y327000D03*
X410000Y338000D03*
X406610Y353410D03*
X409000Y371339D03*
X405463Y383000D03*
X410463D03*
X398500Y391000D03*
X420500Y82000D03*
X425000Y87700D03*
X429000Y123500D03*
X422000D03*
X418500Y117000D03*
X415000Y123500D03*
X426564Y143005D03*
Y186311D03*
X425400Y229600D03*
X420500Y229500D03*
X414900Y229800D03*
X423000Y235400D03*
X416100D03*
X429000Y274000D03*
X424900Y284300D03*
X423900Y278500D03*
X424900Y292900D03*
X429442Y310075D03*
X422500Y354500D03*
X421360Y359970D03*
X420500Y366000D03*
X415463Y383000D03*
X441400Y78100D03*
X438374Y202059D03*
X442311Y209933D03*
X436749Y225000D03*
X443500Y231500D03*
X436500Y237500D03*
X443500Y236500D03*
X447000Y283000D03*
X446000Y294000D03*
X441500Y297500D03*
X447000Y321998D03*
X440000Y332500D03*
X433500Y366500D03*
X433382Y360466D03*
X438500Y364500D03*
X430000Y386500D03*
Y381000D03*
X444000Y406500D03*
X431900Y392200D03*
X431169Y401169D03*
X431000Y406500D03*
X444000Y411500D03*
X431000D03*
X458500Y86500D03*
X461996Y162690D03*
X454122Y217807D03*
X449000Y232500D03*
Y227500D03*
X461000Y230000D03*
X448500Y237500D03*
X454000Y312500D03*
X448500Y311500D03*
X450000Y416500D03*
Y411500D03*
X479500Y92500D03*
X482000Y83500D03*
X475500Y82500D03*
X470500D03*
X466500Y110400D03*
X471200Y115700D03*
X481600Y125800D03*
X476800Y120700D03*
X473807Y154816D03*
X465933Y162690D03*
X473807Y150879D03*
X475000Y163000D03*
X481000Y172500D03*
X479246Y178464D03*
X481500Y193000D03*
X482000Y212500D03*
X480288Y203788D03*
X465933Y202059D03*
X471000Y259200D03*
X467000Y355500D03*
X478500Y346000D03*
X470462Y369462D03*
X470500Y395000D03*
X482800Y110300D03*
X483000Y133000D03*
X490970Y133500D03*
Y138500D03*
X485000Y154000D03*
X497500Y148500D03*
X491000Y154000D03*
X491500Y148500D03*
X497000Y154000D03*
X484000Y166000D03*
X497000Y175000D03*
X498060Y185500D03*
X483871Y198241D03*
X484000Y185500D03*
X492500Y226000D03*
X483100Y272800D03*
X497000Y341000D03*
X483501Y346000D03*
X488500Y359000D03*
X493500D03*
X503005Y99494D03*
X514500Y144000D03*
X503000Y155000D03*
X503500Y149000D03*
X501000Y263500D03*
X500500Y271100D03*
X500000Y278799D03*
X503000Y354600D03*
X503500Y394500D03*
X521500Y60000D03*
X529500Y60500D03*
X519500Y75500D03*
Y81500D03*
X520000Y87000D03*
X533200Y220000D03*
X534500Y253600D03*
X522400Y270700D03*
X522600Y276200D03*
X527500Y389100D03*
X530000Y406500D03*
X527500Y397100D03*
X532300Y425700D03*
X549000Y63500D03*
X549500Y69400D03*
X544500Y79500D03*
X536500Y84500D03*
Y79000D03*
X541000Y96000D03*
X547211Y209800D03*
X541000Y216400D03*
X540600Y234600D03*
X548300Y222600D03*
X548158Y228033D03*
X545250Y256300D03*
X539977Y275124D03*
X540318Y270436D03*
X537500Y296607D03*
X539500Y292000D03*
X543000Y360000D03*
X548557Y387700D03*
X540600Y386300D03*
X537200Y396300D03*
X550643Y400900D03*
X548829Y416329D03*
X548500Y411000D03*
X538558Y413779D03*
X550369Y427558D03*
X538558D03*
X568600Y76000D03*
X558000Y161500D03*
X558900Y202500D03*
X553122Y227979D03*
X559500Y228000D03*
X566700Y227500D03*
X564350Y238443D03*
X561700Y320300D03*
X562500Y326100D03*
X566000Y347000D03*
X563700Y352400D03*
X568000Y356700D03*
X560000Y342100D03*
X568100Y366400D03*
Y361700D03*
X568326Y371200D03*
X563800Y390700D03*
X567500Y386500D03*
X568600Y376000D03*
Y380700D03*
X555569Y388051D03*
X560000Y401000D03*
X564400Y396700D03*
X561731Y408500D03*
X567126Y417500D03*
X555315D03*
X562180Y413779D03*
Y427558D03*
X572500Y60301D03*
X572870Y67570D03*
X580000Y104800D03*
X576500Y98000D03*
X586500Y107000D03*
Y112500D03*
X576500Y219700D03*
X577100Y227900D03*
X569943Y223300D03*
X576000Y246500D03*
X581400Y262100D03*
Y272100D03*
Y282100D03*
X581500Y302100D03*
X576200Y342500D03*
X571800Y396500D03*
X578937Y417500D03*
X572500Y413500D03*
X585500Y409500D03*
X573991Y427558D03*
X600850Y112350D03*
X592000Y136000D03*
Y141000D03*
Y146000D03*
Y163000D03*
Y151500D03*
Y157063D03*
Y173000D03*
Y178000D03*
Y168000D03*
X587000Y184000D03*
X597000Y199900D03*
X587500Y190000D03*
X602500Y183000D03*
X591902Y200300D03*
X601902Y200100D03*
X594153Y220500D03*
X601953Y218853D03*
X595500Y239000D03*
X589953Y236600D03*
X604000Y254500D03*
X591000Y261500D03*
Y271500D03*
Y278500D03*
X590500Y301500D03*
X591000Y291500D03*
X602500Y404000D03*
X591000D03*
X602559Y417500D03*
X590748Y418725D03*
X597613Y413779D03*
Y427558D03*
X606902Y186000D03*
Y200400D03*
X609500Y254500D03*
X614500Y403500D03*
X614370Y417500D03*
X609424Y413779D03*
Y427558D03*
X633500Y108000D03*
Y102000D03*
Y96500D03*
X622000Y141500D03*
Y146500D03*
Y162000D03*
Y151600D03*
Y157000D03*
Y181500D03*
Y175500D03*
X622035Y167063D03*
X623000Y205375D03*
X633500Y205906D03*
X633000Y267000D03*
Y286500D03*
G54D50*
G01X55000Y355400D02*
Y352200D01*
X49800Y347000D01*
X34500D01*
X31694Y344194D01*
Y343150D01*
G54D41*
X574250Y263750D03*
X573750Y292250D03*
G54D14*
X29528Y36811D03*
Y373031D03*
X640039Y65354D03*
Y417835D03*
G54D32*
X269000Y219350D03*
X265260D03*
Y230650D03*
X272740Y219350D03*
Y230650D03*
G54D23*
X126067Y104043D03*
Y184043D03*
Y264043D03*
X253967Y93443D03*
X265967D03*
X277867D03*
X286067Y104043D03*
Y264043D03*
G54D51*
G01X329433Y-125500D02*
Y-133000D01*
X333167D01*
G01X340480D02*
Y-128000D01*
G01Y-128875D02*
X340107Y-128375D01*
X339547Y-128125D01*
X338893Y-128000D01*
X338240Y-128250D01*
X337680Y-128750D01*
X337307Y-129500D01*
X337120Y-130500D01*
X337307Y-131500D01*
X337680Y-132250D01*
X338240Y-132750D01*
X338893Y-133000D01*
X339547Y-132875D01*
X340107Y-132500D01*
X340480Y-132000D01*
G01X344340Y-135250D02*
X344900Y-135500D01*
X345647Y-135250D01*
X346113Y-134750D01*
X346487Y-134125D01*
X347047Y-132125D01*
X348260Y-128000D01*
G01X345273D02*
X347047Y-132125D01*
G01X352400Y-129625D02*
X355387D01*
X355107Y-128750D01*
X354640Y-128250D01*
X353987Y-128000D01*
X353333Y-128125D01*
X352773Y-128500D01*
X352400Y-129375D01*
X352213Y-130125D01*
Y-130875D01*
X352400Y-131625D01*
X352867Y-132375D01*
X353427Y-132875D01*
X354080Y-133000D01*
X354733Y-132750D01*
X355387Y-132000D01*
G01X359993Y-133000D02*
Y-128000D01*
G01Y-129000D02*
X360460Y-128500D01*
X360927Y-128125D01*
X361580Y-128000D01*
X362047Y-128125D01*
X362607Y-128500D01*
G01X368800Y-133250D02*
X368613Y-133125D01*
Y-132875D01*
X368800Y-132750D01*
X368987Y-132875D01*
Y-133125D01*
X368800Y-133250D01*
G01Y-129875D02*
X368613Y-129750D01*
Y-129500D01*
X368800Y-129375D01*
X368987Y-129500D01*
Y-129750D01*
X368800Y-129875D01*
G01X336747Y-120500D02*
Y-113000D01*
X338613D01*
X339360Y-113375D01*
X339920Y-113875D01*
X340387Y-114625D01*
X340760Y-115500D01*
X340853Y-116750D01*
X340760Y-118000D01*
X340387Y-118875D01*
X339920Y-119625D01*
X339360Y-120125D01*
X338613Y-120500D01*
X336747D01*
G01X347980D02*
Y-115500D01*
G01Y-116375D02*
X347607Y-115875D01*
X347047Y-115625D01*
X346393Y-115500D01*
X345740Y-115750D01*
X345180Y-116250D01*
X344807Y-117000D01*
X344620Y-118000D01*
X344807Y-119000D01*
X345180Y-119750D01*
X345740Y-120250D01*
X346393Y-120500D01*
X347047Y-120375D01*
X347607Y-120000D01*
X347980Y-119500D01*
G01X353800Y-113000D02*
Y-120500D01*
G01X352493Y-115500D02*
X355107D01*
G01X359900Y-117125D02*
X362887D01*
X362607Y-116250D01*
X362140Y-115750D01*
X361487Y-115500D01*
X360833Y-115625D01*
X360273Y-116000D01*
X359900Y-116875D01*
X359713Y-117625D01*
Y-118375D01*
X359900Y-119125D01*
X360367Y-119875D01*
X360927Y-120375D01*
X361580Y-120500D01*
X362233Y-120250D01*
X362887Y-119500D01*
G01X368800Y-120750D02*
X368613Y-120625D01*
Y-120375D01*
X368800Y-120250D01*
X368987Y-120375D01*
Y-120625D01*
X368800Y-120750D01*
G01Y-117375D02*
X368613Y-117250D01*
Y-117000D01*
X368800Y-116875D01*
X368987Y-117000D01*
Y-117250D01*
X368800Y-117375D01*
G01X382027Y-114250D02*
X382587Y-113500D01*
X383240Y-113125D01*
X383987Y-113000D01*
X384920Y-113250D01*
X385573Y-113875D01*
X385760Y-114625D01*
X385667Y-115375D01*
X385293Y-116000D01*
X383427Y-117250D01*
X382587Y-118125D01*
X382027Y-119375D01*
X381840Y-120500D01*
X385760D01*
G01X391300Y-113000D02*
X390553Y-113250D01*
X389993Y-113875D01*
X389620Y-114625D01*
X389340Y-115625D01*
X389247Y-116750D01*
X389340Y-117875D01*
X389620Y-118875D01*
X389993Y-119625D01*
X390553Y-120250D01*
X391300Y-120500D01*
X392047Y-120250D01*
X392607Y-119625D01*
X392980Y-118875D01*
X393260Y-117875D01*
X393353Y-116750D01*
X393260Y-115625D01*
X392980Y-114625D01*
X392607Y-113875D01*
X392047Y-113250D01*
X391300Y-113000D01*
G01X397027Y-114250D02*
X397587Y-113500D01*
X398240Y-113125D01*
X398987Y-113000D01*
X399920Y-113250D01*
X400573Y-113875D01*
X400760Y-114625D01*
X400667Y-115375D01*
X400293Y-116000D01*
X398427Y-117250D01*
X397587Y-118125D01*
X397027Y-119375D01*
X396840Y-120500D01*
X400760D01*
G01X404527Y-114250D02*
X405087Y-113500D01*
X405740Y-113125D01*
X406487Y-113000D01*
X407420Y-113250D01*
X408073Y-113875D01*
X408260Y-114625D01*
X408167Y-115375D01*
X407793Y-116000D01*
X405927Y-117250D01*
X405087Y-118125D01*
X404527Y-119375D01*
X404340Y-120500D01*
X408260D01*
G01X412587Y-118000D02*
X415013D01*
G01X421300Y-113000D02*
X420553Y-113250D01*
X419993Y-113875D01*
X419620Y-114625D01*
X419340Y-115625D01*
X419247Y-116750D01*
X419340Y-117875D01*
X419620Y-118875D01*
X419993Y-119625D01*
X420553Y-120250D01*
X421300Y-120500D01*
X422047Y-120250D01*
X422607Y-119625D01*
X422980Y-118875D01*
X423260Y-117875D01*
X423353Y-116750D01*
X423260Y-115625D01*
X422980Y-114625D01*
X422607Y-113875D01*
X422047Y-113250D01*
X421300Y-113000D01*
G01X427027Y-114250D02*
X427587Y-113500D01*
X428240Y-113125D01*
X428987Y-113000D01*
X429920Y-113250D01*
X430573Y-113875D01*
X430760Y-114625D01*
X430667Y-115375D01*
X430293Y-116000D01*
X428427Y-117250D01*
X427587Y-118125D01*
X427027Y-119375D01*
X426840Y-120500D01*
X430760D01*
G01X435087Y-118000D02*
X437513D01*
G01X442027Y-114250D02*
X442587Y-113500D01*
X443240Y-113125D01*
X443987Y-113000D01*
X444920Y-113250D01*
X445573Y-113875D01*
X445760Y-114625D01*
X445667Y-115375D01*
X445293Y-116000D01*
X443427Y-117250D01*
X442587Y-118125D01*
X442027Y-119375D01*
X441840Y-120500D01*
X445760D01*
G01X449247Y-119375D02*
X449807Y-120000D01*
X450460Y-120375D01*
X451300Y-120500D01*
X452140Y-120250D01*
X452793Y-119750D01*
X453260Y-118875D01*
X453353Y-117875D01*
X453167Y-116875D01*
X452700Y-116250D01*
X452047Y-115750D01*
X451393Y-115625D01*
X450740Y-115750D01*
X449900Y-116250D01*
X450180Y-113000D01*
X452700D01*
G01X336933Y-108000D02*
Y-100500D01*
X339267D01*
X340013Y-100875D01*
X340480Y-101375D01*
X340667Y-102375D01*
X340480Y-103375D01*
X339920Y-104000D01*
X339267Y-104375D01*
X336933D01*
G01X339267D02*
X340667Y-108000D01*
G01X344900Y-104625D02*
X347887D01*
X347607Y-103750D01*
X347140Y-103250D01*
X346487Y-103000D01*
X345833Y-103125D01*
X345273Y-103500D01*
X344900Y-104375D01*
X344713Y-105125D01*
Y-105875D01*
X344900Y-106625D01*
X345367Y-107375D01*
X345927Y-107875D01*
X346580Y-108000D01*
X347233Y-107750D01*
X347887Y-107000D01*
G01X352120Y-103000D02*
X353800Y-108000D01*
X355480Y-103000D01*
G01X368800Y-108250D02*
X368613Y-108125D01*
Y-107875D01*
X368800Y-107750D01*
X368987Y-107875D01*
Y-108125D01*
X368800Y-108250D01*
G01Y-104875D02*
X368613Y-104750D01*
Y-104500D01*
X368800Y-104375D01*
X368987Y-104500D01*
Y-104750D01*
X368800Y-104875D01*
G01X383800Y-100500D02*
X383053Y-100750D01*
X382493Y-101375D01*
X382120Y-102125D01*
X381840Y-103125D01*
X381747Y-104250D01*
X381840Y-105375D01*
X382120Y-106375D01*
X382493Y-107125D01*
X383053Y-107750D01*
X383800Y-108000D01*
X384547Y-107750D01*
X385107Y-107125D01*
X385480Y-106375D01*
X385760Y-105375D01*
X385853Y-104250D01*
X385760Y-103125D01*
X385480Y-102125D01*
X385107Y-101375D01*
X384547Y-100750D01*
X383800Y-100500D01*
G01X391300Y-108000D02*
Y-100500D01*
X390180Y-102000D01*
G01Y-108000D02*
X392420D01*
G01X336933Y-95500D02*
Y-88000D01*
X339173D01*
X339920Y-88375D01*
X340480Y-89250D01*
X340667Y-90250D01*
X340480Y-91250D01*
X340013Y-92000D01*
X339173Y-92375D01*
X336933D01*
G01X344620Y-95750D02*
X347980Y-88000D01*
G01X351653Y-95500D02*
Y-88000D01*
X355947Y-95500D01*
Y-88000D01*
G01X368800Y-95750D02*
X368613Y-95625D01*
Y-95375D01*
X368800Y-95250D01*
X368987Y-95375D01*
Y-95625D01*
X368800Y-95750D01*
G01Y-92375D02*
X368613Y-92250D01*
Y-92000D01*
X368800Y-91875D01*
X368987Y-92000D01*
Y-92250D01*
X368800Y-92375D01*
G01X381933Y-95500D02*
Y-88000D01*
X384267D01*
X385013Y-88375D01*
X385480Y-88875D01*
X385667Y-89875D01*
X385480Y-90875D01*
X384920Y-91500D01*
X384267Y-91875D01*
X381933D01*
G01X384267D02*
X385667Y-95500D01*
G01X392420D02*
Y-88000D01*
X388967Y-93375D01*
X393633D01*
G01X398800Y-88000D02*
X398053Y-88250D01*
X397493Y-88875D01*
X397120Y-89625D01*
X396840Y-90625D01*
X396747Y-91750D01*
X396840Y-92875D01*
X397120Y-93875D01*
X397493Y-94625D01*
X398053Y-95250D01*
X398800Y-95500D01*
X399547Y-95250D01*
X400107Y-94625D01*
X400480Y-93875D01*
X400760Y-92875D01*
X400853Y-91750D01*
X400760Y-90625D01*
X400480Y-89625D01*
X400107Y-88875D01*
X399547Y-88250D01*
X398800Y-88000D01*
G01X406300D02*
X405553Y-88250D01*
X404993Y-88875D01*
X404620Y-89625D01*
X404340Y-90625D01*
X404247Y-91750D01*
X404340Y-92875D01*
X404620Y-93875D01*
X404993Y-94625D01*
X405553Y-95250D01*
X406300Y-95500D01*
X407047Y-95250D01*
X407607Y-94625D01*
X407980Y-93875D01*
X408260Y-92875D01*
X408353Y-91750D01*
X408260Y-90625D01*
X407980Y-89625D01*
X407607Y-88875D01*
X407047Y-88250D01*
X406300Y-88000D01*
G01X412027Y-92375D02*
X412680Y-91500D01*
X413240Y-91000D01*
X413987Y-90750D01*
X414640Y-91000D01*
X415107Y-91500D01*
X415480Y-92250D01*
X415573Y-93125D01*
X415480Y-93875D01*
X415107Y-94625D01*
X414547Y-95250D01*
X413893Y-95500D01*
X413147Y-95250D01*
X412493Y-94500D01*
X412120Y-93375D01*
X412027Y-92125D01*
X412213Y-90500D01*
X412493Y-89625D01*
X412960Y-88750D01*
X413613Y-88125D01*
X414267Y-88000D01*
X414920Y-88250D01*
X415387Y-88875D01*
G01X420087Y-93000D02*
X422513D01*
G01X429547Y-91500D02*
X429920Y-91125D01*
X430200Y-90500D01*
X430387Y-89625D01*
X430200Y-88875D01*
X429827Y-88375D01*
X429173Y-88000D01*
X426653D01*
Y-95500D01*
X429733D01*
X430387Y-95000D01*
X430760Y-94250D01*
X430947Y-93375D01*
X430760Y-92500D01*
X430200Y-91750D01*
X429547Y-91500D01*
X426653D01*
G01X436300Y-88000D02*
X435553Y-88250D01*
X434993Y-88875D01*
X434620Y-89625D01*
X434340Y-90625D01*
X434247Y-91750D01*
X434340Y-92875D01*
X434620Y-93875D01*
X434993Y-94625D01*
X435553Y-95250D01*
X436300Y-95500D01*
X437047Y-95250D01*
X437607Y-94625D01*
X437980Y-93875D01*
X438260Y-92875D01*
X438353Y-91750D01*
X438260Y-90625D01*
X437980Y-89625D01*
X437607Y-88875D01*
X437047Y-88250D01*
X436300Y-88000D01*
G01X443800D02*
X443053Y-88250D01*
X442493Y-88875D01*
X442120Y-89625D01*
X441840Y-90625D01*
X441747Y-91750D01*
X441840Y-92875D01*
X442120Y-93875D01*
X442493Y-94625D01*
X443053Y-95250D01*
X443800Y-95500D01*
X444547Y-95250D01*
X445107Y-94625D01*
X445480Y-93875D01*
X445760Y-92875D01*
X445853Y-91750D01*
X445760Y-90625D01*
X445480Y-89625D01*
X445107Y-88875D01*
X444547Y-88250D01*
X443800Y-88000D01*
G01X451300D02*
X450553Y-88250D01*
X449993Y-88875D01*
X449620Y-89625D01*
X449340Y-90625D01*
X449247Y-91750D01*
X449340Y-92875D01*
X449620Y-93875D01*
X449993Y-94625D01*
X450553Y-95250D01*
X451300Y-95500D01*
X452047Y-95250D01*
X452607Y-94625D01*
X452980Y-93875D01*
X453260Y-92875D01*
X453353Y-91750D01*
X453260Y-90625D01*
X452980Y-89625D01*
X452607Y-88875D01*
X452047Y-88250D01*
X451300Y-88000D01*
G01X458800Y-95500D02*
Y-88000D01*
X457680Y-89500D01*
G01Y-95500D02*
X459920D01*
G01X465087Y-93000D02*
X467513D01*
G01X473800Y-88000D02*
X473053Y-88250D01*
X472493Y-88875D01*
X472120Y-89625D01*
X471840Y-90625D01*
X471747Y-91750D01*
X471840Y-92875D01*
X472120Y-93875D01*
X472493Y-94625D01*
X473053Y-95250D01*
X473800Y-95500D01*
X474547Y-95250D01*
X475107Y-94625D01*
X475480Y-93875D01*
X475760Y-92875D01*
X475853Y-91750D01*
X475760Y-90625D01*
X475480Y-89625D01*
X475107Y-88875D01*
X474547Y-88250D01*
X473800Y-88000D01*
G01X479527Y-89250D02*
X480087Y-88500D01*
X480740Y-88125D01*
X481487Y-88000D01*
X482420Y-88250D01*
X483073Y-88875D01*
X483260Y-89625D01*
X483167Y-90375D01*
X482793Y-91000D01*
X480927Y-92250D01*
X480087Y-93125D01*
X479527Y-94375D01*
X479340Y-95500D01*
X483260D01*
G54D33*
X285000Y227700D03*
Y234300D03*
X296000Y284700D03*
X303500D03*
X296000Y291300D03*
X303500D03*
X311000Y284700D03*
Y291300D03*
X318500Y375700D03*
Y382300D03*
X346000Y131200D03*
Y137800D03*
X378500Y130200D03*
Y136800D03*
X366200Y295200D03*
Y301800D03*
X540000Y178700D03*
Y185300D03*
G54D42*
X588779Y334449D03*
Y350984D03*
Y367519D03*
X605315Y334449D03*
Y350984D03*
G54D24*
X147200Y409000D03*
X141800D03*
X351600Y388700D03*
X357000D03*
X361800Y139500D03*
X367200D03*
G54D15*
X19878Y36811D03*
X22704Y29987D03*
Y43635D03*
X22834Y340080D03*
X26378D03*
X28150Y343150D03*
X24606D03*
X19878Y373031D03*
X22704Y366207D03*
Y379855D03*
X29528Y27161D03*
X36352Y29987D03*
X39178Y36811D03*
X36352Y43635D03*
X29528Y46461D03*
X29922Y340080D03*
X33466D03*
X37010D03*
X40554D03*
X44098D03*
X45870Y343150D03*
X42326D03*
X38782D03*
X35238D03*
X31694D03*
X29528Y363381D03*
X36352Y366207D03*
X39178Y373031D03*
X36352Y379855D03*
X29528Y382681D03*
X633215Y58530D03*
Y72178D03*
X630389Y65354D03*
X633215Y424659D03*
X630389Y417835D03*
X633215Y411011D03*
X640039Y55704D03*
X646863Y58530D03*
X649689Y65354D03*
X646863Y72178D03*
X640039Y75004D03*
Y408185D03*
X646863Y411011D03*
X649689Y417835D03*
X646863Y424659D03*
X640039Y427485D03*
G54D52*
G01X145964Y-110118D02*
G03I-634J0D01*
G01X149695D02*
G03I-1038J0D01*
G01X168013Y-137456D02*
G03I-634J0D01*
G01X155900Y-133655D02*
G03I-632J0D01*
G01X161735Y-128639D02*
G03I-1458J0D01*
G01X158530Y-131428D02*
G03I-1041J0D01*
G01X158461Y-119126D02*
G03I-1283J0D01*
G01X162690Y-117490D02*
G03I-1584J0D01*
G01X169809Y-121292D02*
G03I-2180J0D01*
G01X165531Y-125255D02*
G03I-1869J0D01*
G01X167813Y-115513D02*
G03I-1971J0D01*
G01X154775Y-120500D02*
G03I-892J0D01*
G01X162681Y-102774D02*
G03I-1584J0D01*
G01X158451Y-101149D02*
G03I-1283J0D01*
G01X159258Y-110118D02*
G03I-1868J0D01*
G01X169812Y-98951D02*
G03I-2180J0D01*
G01X167802Y-104739D02*
G03I-1971J0D01*
G01X165183Y-110118D02*
G03I-2180J0D01*
G01X171881D02*
G03I-2642J0D01*
G01X152135Y-98681D02*
G03I-632J0D01*
G01X154064Y-110118D02*
G03I-1460J0D01*
G01X154764Y-99775D02*
G03I-892J0D01*
G01X158530Y-88809D02*
G03I-1041J0D01*
G01X161742Y-91601D02*
G03I-1458J0D01*
G01X165531Y-94981D02*
G03I-1869J0D01*
G01X171080Y-131739D02*
G03I-1282J0D01*
G01X169322Y-135033D02*
G03I-892J0D01*
G01X180669Y-131528D02*
G03I-1870J0D01*
G01X180255Y-136311D02*
G03I-1456J0D01*
G01X179841Y-140261D02*
G03I-1042J0D01*
G01X179433Y-143587D02*
G03I-634J0D01*
G01X181439Y-119680D02*
G03I-2640J0D01*
G01X175373Y-123081D02*
G03I-1968J0D01*
G01X173018Y-127816D02*
G03I-1584J0D01*
G01X174681Y-116876D02*
G03I-2640J0D01*
G01X180979Y-125917D02*
G03I-2180J0D01*
G01X186177Y-123075D02*
G03I-1971J0D01*
G01X188199Y-116876D02*
G03I-2640J0D01*
G01X175452Y-97124D02*
G03I-1968J0D01*
G01X186225Y-97178D02*
G03I-1971J0D01*
G01X181439Y-100556D02*
G03I-2640J0D01*
G01X174681Y-103361D02*
G03I-2640J0D01*
G01X188199D02*
G03I-2640J0D01*
G01X179841Y-79975D02*
G03I-1042J0D01*
G01X171217Y-88444D02*
G03I-1282J0D01*
G01X173123Y-92378D02*
G03I-1584J0D01*
G01X180255Y-83924D02*
G03I-1456J0D01*
G01X180669Y-88708D02*
G03I-1870J0D01*
G01X180979Y-94320D02*
G03I-2180J0D01*
G01X179433Y-76648D02*
G03I-634J0D01*
G01X191096Y-134658D02*
G03I-892J0D01*
G01X192135Y-136781D02*
G03I-631J0D01*
G01X198775Y-128635D02*
G03I-1458J0D01*
G01X195808Y-125255D02*
G03I-1869J0D01*
G01X200547Y-113952D02*
G03X203345Y-117196I7247J3422D01*
G01X192148Y-121285D02*
G03I-2180J0D01*
G01X187928Y-127802D02*
G03I-1584J0D01*
G01X189667Y-131511D02*
G03I-1283J0D01*
G01X200699Y-105836D02*
G03X200547Y-113953I8974J-4228D01*
G01X208284Y-101612D02*
G03X200698Y-105835I-219J-8531D01*
G01X192148Y-98951D02*
G03I-2180J0D01*
G01X191108Y-82727D02*
G03I-634J0D01*
G01X190184Y-85250D02*
G03I-893J0D01*
G01X195808Y-94981D02*
G03I-1869J0D01*
G01X187839Y-92457D02*
G03I-1584J0D01*
G01X189190Y-88538D02*
G03I-1283J0D01*
G01X214259Y-115661D02*
G03X213314Y-114453I-714J415D01*
G01X202049Y-108260D02*
G03X205722Y-116181I7039J-1548D01*
G01X218075Y-112869D02*
G03X219083Y-115752I4343J-99D01*
G01X208854Y-116658D02*
G03X213313Y-114452I-2485J10632D01*
G01X208470Y-118462D02*
G03X214261Y-115663I-1122J9711D01*
G01X203346Y-117195D02*
G03X208470Y-118461I4545J7394D01*
G01X205721Y-116179D02*
G03X208853Y-116659I2561J6250D01*
G01X215903Y-114020D02*
G03X219079Y-118061I6190J1597D01*
G01X215904Y-114020D02*
Y-111835D01*
G01X227413Y-112869D02*
X218074D01*
G01X214175Y-103951D02*
G03X208283Y-101613I-6403J-7542D01*
G01X213150Y-105147D02*
G03X214175Y-103951I410J686D01*
G01X213152Y-105146D02*
G03X208030Y-103430I-5122J-6786D01*
G01X208029Y-103429D02*
G03X202049Y-108259I-48J-6058D01*
G01X225189Y-111399D02*
G03X218071I-3559J159D01*
G01X218070Y-111418D02*
Y-111399D01*
G01X225188Y-111418D02*
X218070D01*
G01X227412Y-111835D02*
G03X215906I-5753J223D01*
G01X230059Y-117625D02*
Y-102034D01*
G01X230060Y-117626D02*
G03X232080I1010J239D01*
G01X226590Y-116472D02*
G03X225311Y-115210I-817J451D01*
G01X234673Y-114020D02*
G03X237849Y-118061I6190J1597D01*
G01X232081Y-102041D02*
Y-117625D01*
G01X219083Y-115753D02*
G03X225311Y-115211I2844J3371D01*
G01X219079Y-118060D02*
G03X226591Y-116473I2662J5972D01*
G01X227413Y-111835D02*
Y-112869D01*
G01X232080Y-102041D02*
G03X230060Y-102034I-1011J-236D01*
G01X225188Y-111399D02*
Y-111418D01*
G01X234675Y-114020D02*
Y-111835D01*
G01X246181D02*
G03X234675I-5753J223D01*
G01X252849Y-116771D02*
G03X254892Y-115895I-74J2994D01*
G01X236844Y-112869D02*
G03X237852Y-115752I4343J-99D01*
G01X237848Y-118060D02*
G03X245360Y-116473I2662J5972D01*
G01X245358Y-116472D02*
G03X244079Y-115210I-817J451D01*
G01X237852Y-115753D02*
G03X244080Y-115211I2844J3371D01*
G01X249566Y-115529D02*
G03X252307Y-116760I2985J2980D01*
G01Y-116761D02*
G03X252849Y-116772I366J4691D01*
G01X250282Y-118087D02*
G03X254318Y-118340I2605J9244D01*
G01X247897Y-116444D02*
G03X250283Y-118086I3752J2898D01*
G01X249568Y-115529D02*
G03X247898Y-116443I-748J-616D01*
G01X255608Y-108618D02*
G03X253612Y-107689I-3116J-4086D01*
G01X246181Y-111835D02*
Y-112869D01*
G01D02*
X236844D01*
G01X255002Y-114328D02*
G03X252723Y-112986I-3540J-3405D01*
G01X249955Y-112030D02*
G03X252723Y-112985I8208J19302D01*
G01X243957Y-111399D02*
Y-111418D01*
G01X243958Y-111399D02*
G03X236840I-3559J159D01*
G01X236841Y-111418D02*
Y-111399D01*
G01X243957Y-111418D02*
X236841D01*
G01X248537Y-109748D02*
G03X249956Y-112031I2652J66D01*
G01X248537Y-108250D02*
Y-109748D01*
G01X250179Y-106359D02*
G03X248537Y-108249I2747J-4045D01*
G01X256884Y-107368D02*
G03X250178Y-106359I-4153J-4811D01*
G01X253611Y-107689D02*
G03X251080Y-107949I-869J-3992D01*
G01X251081Y-107948D02*
G03X250837Y-110104I805J-1183D01*
G01Y-110106D02*
G03X254306Y-111513I5270J8013D01*
G01X260954Y-116041D02*
Y-107954D01*
G01X254892Y-115895D02*
G03X255001Y-114328I-764J840D01*
G01X269619Y-117484D02*
Y-106797D01*
G01X269620Y-117484D02*
G03X271926I1153J198D01*
G01X266864Y-117375D02*
G03X266002Y-116329I-764J249D01*
G01X262978Y-115462D02*
G03X266002Y-116329I2046J1428D01*
G01X260955Y-116043D02*
G03X264164Y-118351I2956J725D01*
G01X265463Y-118350D02*
X264165D01*
G01X265464Y-118352D02*
G03X266864Y-117374I-24J1525D01*
G01X256906Y-116470D02*
G03X257054Y-113728I-3143J1545D01*
G01X254317Y-118340D02*
G03X256906Y-116470I-1259J4470D01*
G01X262978Y-107954D02*
Y-115463D01*
G01X257054Y-113729D02*
G03X254307Y-111513I-3470J-1490D01*
G01X271969Y-102342D02*
G03I-1194J0D01*
G01X271926Y-106797D02*
G03X269620I-1153J-409D01*
G01X266003Y-107954D02*
X262978D01*
G01X266004Y-107955D02*
G03X266008Y-105932I-177J1012D01*
G01X262978D02*
X266008D01*
G01X262971Y-103419D02*
X262978Y-105932D01*
G01X262972Y-103418D02*
G03X260954Y-103491I-1005J-141D01*
G01Y-105932D02*
Y-103492D01*
G01X259930Y-105932D02*
X260954D01*
G01X259930D02*
G03X259981Y-107955I298J-1005D01*
G01X260954Y-107954D02*
X259982D01*
G01X255606Y-108620D02*
G03X256885Y-107367I599J667D01*
G01X290671Y-110842D02*
G03X290703Y-118351I860J-3751D01*
G01X276837Y-114305D02*
G03X278891Y-116297I4069J2141D01*
G01X274529Y-113568D02*
G03X275888Y-116443I5718J944D01*
G01X275887D02*
G03X279572Y-118352I4392J3967D01*
G01X281425Y-118350D02*
X279571D01*
G01X281425D02*
G03X284525Y-117161I0J4636D01*
G01X285201Y-116508D02*
X284524Y-117161D01*
G01X285201Y-116508D02*
G03X283966Y-115211I-695J574D01*
G01X281510Y-116675D02*
G03X283966Y-115212I-989J4453D01*
G01X278889Y-116297D02*
G03X281508Y-116677I1946J4197D01*
G01X271926Y-106797D02*
Y-117484D01*
G01X274529Y-113566D02*
Y-111839D01*
G01X276446Y-112943D02*
G03X276837Y-114305I4162J458D01*
G01X276445Y-112066D02*
Y-112943D01*
G01X283833Y-109274D02*
G03X285403Y-108106I585J852D01*
G01X285402D02*
G03X280919Y-105777I-4776J-3714D01*
G01X279541D02*
X280919D01*
G01X279540D02*
G03X274999Y-109274I1260J-6333D01*
G01X274998D02*
G03X274529Y-111839I9988J-3152D01*
G01X276849Y-109932D02*
G03X276446Y-112066I5467J-2137D01*
G01X280036Y-107542D02*
G03X276849Y-109933I664J-4205D01*
G01X282662Y-108199D02*
G03X280037Y-107539I-2313J-3650D01*
G01X283833Y-109275D02*
G03X282662Y-108202I-9277J-8949D01*
G01X294457Y-116619D02*
G03Y-112289I-51J2165D01*
G01X291853Y-116620D02*
X294456D01*
G01X291853Y-112289D02*
G03Y-116619I195J-2165D01*
G01X294165Y-118350D02*
X290701D01*
G01X294165D02*
G03X296471Y-117226I-1088J5161D01*
G01X296473Y-117625D02*
Y-117226D01*
G01X296474Y-117627D02*
G03X298494I1010J185D01*
G01X298495Y-109394D02*
Y-117625D01*
G01X301067Y-108534D02*
Y-106508D01*
G01X301615Y-108534D02*
X301067D01*
G01X301615Y-106508D02*
Y-108534D01*
G01X302461Y-106508D02*
X301615D01*
G01X302461Y-106001D02*
Y-106508D01*
G01X300223Y-106001D02*
X302461D01*
G01X300223Y-106508D02*
Y-106001D01*
G01X301067Y-106508D02*
X300223D01*
G01X305164Y-106001D02*
X304731D01*
G01X305713Y-108544D02*
X305164Y-106001D01*
G01X305171Y-108544D02*
X305713D01*
G01X304889Y-106871D02*
X305171Y-108544D01*
G01X304309D02*
X304889Y-106871D01*
G01X304086Y-108544D02*
X304309D01*
G01X303501Y-106887D02*
X304086Y-108544D01*
G01X303226D02*
X303501Y-106887D01*
G01X302698Y-108544D02*
X303226D01*
G01X303243Y-106001D02*
X302698Y-108544D01*
G01X303648Y-106001D02*
X303243D01*
G01X304192Y-107632D02*
X303648Y-106001D01*
G01X304731D02*
X304192Y-107632D01*
G01X294456Y-112288D02*
X291853D01*
G01X296473Y-110841D02*
Y-109686D01*
G01X296472Y-110841D02*
G03X292878Y-110536I-3256J-17043D01*
G01X292879Y-110535D02*
G03X290670Y-110842I280J-10112D01*
G01X298496Y-109394D02*
G03X295031Y-105933I-3962J-501D01*
G01X291563Y-105932D02*
X295031D01*
G01X291562D02*
G03X289112Y-107085I584J-4421D01*
G01Y-107086D02*
G03X289820Y-108520I585J-603D01*
G01X290987Y-107954D02*
G03X289821Y-108520I1446J-4464D01*
G01X294740Y-107954D02*
X290987D01*
G01X296473Y-109686D02*
G03X294742Y-107955I-1598J133D01*
G01X383800Y-128733D02*
X384200Y-128333D01*
X384500Y-127667D01*
X384700Y-126733D01*
X384500Y-125933D01*
X384100Y-125400D01*
X383400Y-125000D01*
X380700D01*
Y-133000D01*
X384000D01*
X384700Y-132467D01*
X385100Y-131667D01*
X385300Y-130733D01*
X385100Y-129800D01*
X384500Y-129000D01*
X383800Y-128733D01*
X380700D01*
G01X391000Y-133000D02*
X390200Y-132867D01*
X389500Y-132333D01*
X388900Y-131533D01*
X388500Y-130600D01*
X388300Y-129533D01*
Y-128467D01*
X388500Y-127400D01*
X388900Y-126467D01*
X389500Y-125667D01*
X390200Y-125133D01*
X391000Y-125000D01*
X391800Y-125133D01*
X392500Y-125667D01*
X393100Y-126467D01*
X393500Y-127400D01*
X393700Y-128467D01*
Y-129533D01*
X393500Y-130600D01*
X393100Y-131533D01*
X392500Y-132333D01*
X391800Y-132867D01*
X391000Y-133000D01*
G01X399000Y-125000D02*
Y-133000D01*
G01X396700Y-125000D02*
X401300D01*
G01X407000D02*
Y-133000D01*
G01X404700Y-125000D02*
X409300D01*
G01X415000Y-133000D02*
X414200Y-132867D01*
X413500Y-132333D01*
X412900Y-131533D01*
X412500Y-130600D01*
X412300Y-129533D01*
Y-128467D01*
X412500Y-127400D01*
X412900Y-126467D01*
X413500Y-125667D01*
X414200Y-125133D01*
X415000Y-125000D01*
X415800Y-125133D01*
X416500Y-125667D01*
X417100Y-126467D01*
X417500Y-127400D01*
X417700Y-128467D01*
Y-129533D01*
X417500Y-130600D01*
X417100Y-131533D01*
X416500Y-132333D01*
X415800Y-132867D01*
X415000Y-133000D01*
G01X420400D02*
Y-125000D01*
X423000Y-131667D01*
X425600Y-125000D01*
Y-133000D01*
G54D34*
X305350Y214300D03*
X305850Y231500D03*
X297150Y235200D03*
Y227800D03*
X296650Y218000D03*
X305350Y221700D03*
G54D43*
X605315Y367519D03*
G54D16*
X16039Y71260D03*
Y128346D03*
Y185433D03*
Y242520D03*
G54D25*
X162650Y403100D03*
X163550D03*
X337250Y394700D03*
X336350D03*
G54D53*
G01X152100Y399300D02*
X151900Y399100D01*
X147700D01*
G54D44*
X634055Y334449D03*
Y367519D03*
G54D17*
X24100Y297500D03*
X19900D03*
Y302500D03*
X24100D03*
Y292500D03*
X19900D03*
Y287500D03*
X24100D03*
Y307500D03*
X19900D03*
X63500Y61500D03*
X67700D03*
X80900Y66500D03*
X71700Y154400D03*
X67500D03*
X80800Y163900D03*
Y159400D03*
X80400Y150000D03*
X71600Y149500D03*
X67400D03*
X80800Y154900D03*
X71800Y159900D03*
X67600D03*
X80800Y168400D03*
X69900Y291500D03*
X74100D03*
X74600Y320000D03*
X70400D03*
Y315500D03*
X74600D03*
Y324500D03*
X70400D03*
X88900Y71000D03*
X84700D03*
X85100Y66500D03*
X85000Y163900D03*
Y159400D03*
X84600Y150000D03*
X85000Y154900D03*
Y168400D03*
X91100Y345500D03*
X86900D03*
X91100Y350000D03*
X86900D03*
X91100Y341000D03*
X86900D03*
X103800Y71800D03*
X108000D03*
X115400Y347500D03*
X130900Y75300D03*
X117370Y70860D03*
X121570D03*
X121580Y65870D03*
X117380D03*
X130850Y65800D03*
X130870Y70800D03*
X133400Y350000D03*
X119600Y347500D03*
X135100Y75300D03*
X135050Y65800D03*
X135070Y70800D03*
X147900Y300000D03*
X138100Y328000D03*
X133900D03*
X138100Y323500D03*
X133900D03*
X137600Y350000D03*
X147700Y390100D03*
X143500D03*
X146700Y385100D03*
X142500D03*
X147700Y403600D03*
X143500D03*
Y394600D03*
X147700D03*
X143500Y399100D03*
X147700D03*
X143500Y414200D03*
X147700D03*
X152100Y300000D03*
X154000Y377600D03*
X158200D03*
X166600Y388500D03*
X162400D03*
X176600Y391000D03*
X172400D03*
X210400Y336000D03*
X214600D03*
X210400Y355000D03*
X214600D03*
X210400Y350000D03*
X214600D03*
X241900Y235500D03*
X246100D03*
X255100Y237500D03*
X250900D03*
X259900D03*
X264100D03*
X283850Y194500D03*
X279650D03*
X304100Y205000D03*
X299900D03*
X304100Y200500D03*
X299900D03*
X306800Y321000D03*
X302600D03*
Y330500D03*
X306800D03*
X302600Y335000D03*
X306800D03*
Y326000D03*
X302600D03*
X324400Y407000D03*
X341900Y225500D03*
X332900D03*
X337100D03*
Y221000D03*
X332900D03*
X341900D03*
X329800Y320500D03*
X325600D03*
X329800Y329500D03*
X325600D03*
X329800Y334000D03*
X325600D03*
X329800Y338500D03*
X325600D03*
X329800Y325000D03*
X325600D03*
X329800Y347500D03*
X325600D03*
X329800Y343000D03*
X325600D03*
X328600Y407000D03*
X334400Y409500D03*
X338600D03*
X357500Y193149D03*
X353300D03*
X357500Y188649D03*
X353300D03*
X346100Y225500D03*
Y221000D03*
X350600Y337000D03*
X346400D03*
X350600Y332500D03*
X346400D03*
X350600Y328000D03*
X346400D03*
X350600Y323500D03*
X346400D03*
X350600Y341500D03*
X346400D03*
X352200Y394200D03*
X356400D03*
Y403200D03*
X352200D03*
Y407700D03*
X356400D03*
Y398700D03*
X352200D03*
X359400Y419700D03*
X355200D03*
X353900Y413000D03*
X358100D03*
X374600Y172000D03*
X370400D03*
X365100Y217000D03*
X360900D03*
X374400Y323500D03*
Y328000D03*
Y332500D03*
Y337000D03*
Y341500D03*
X387629Y129361D03*
X391829D03*
X384430Y174500D03*
X388630D03*
X383500Y309200D03*
X379300D03*
X393300D03*
X389100D03*
X378600Y323500D03*
Y328000D03*
Y332500D03*
Y337000D03*
Y341500D03*
X383900Y375800D03*
X388100D03*
X383900Y381000D03*
X388100D03*
X409800Y175000D03*
X402400Y221500D03*
X406600D03*
X401500Y323900D03*
X397300D03*
X401500Y329100D03*
X397300D03*
X426900Y73000D03*
X414000Y175000D03*
X419900D03*
X424100D03*
X426600Y406500D03*
X422400D03*
X426600Y411500D03*
X422400D03*
X431100Y73000D03*
X432300Y174100D03*
X436500D03*
X446511Y175500D03*
X442311D03*
X445485Y222000D03*
X436600Y297500D03*
X432400D03*
X435400Y386500D03*
X439600D03*
Y396500D03*
X435400D03*
Y406500D03*
X439600D03*
X435400Y411500D03*
X439600D03*
X455511Y175500D03*
X451311D03*
X463900D03*
X449685Y222000D03*
X456600Y284500D03*
X452400D03*
Y279500D03*
X456600D03*
Y289500D03*
X452400D03*
Y294500D03*
X456600D03*
X461400Y389500D03*
Y394000D03*
X473600Y91500D03*
X469400D03*
X473600Y96500D03*
X469400D03*
X468100Y175500D03*
X473600Y355100D03*
X477800D03*
X465600Y389500D03*
Y394000D03*
X488400Y163000D03*
X492600D03*
Y167500D03*
X488400D03*
X492600Y176500D03*
X488400D03*
Y181000D03*
X492600D03*
X488400Y197500D03*
X492600D03*
X488400Y185500D03*
X492600D03*
Y202500D03*
X488400D03*
X498900Y345500D03*
X503100D03*
X544600Y69000D03*
X540400D03*
Y64000D03*
X544600D03*
X543100Y227500D03*
X538900D03*
X550400Y264000D03*
Y259500D03*
X550200Y272100D03*
X550400Y277000D03*
Y281500D03*
X550200Y292250D03*
X550400Y302000D03*
X549600Y287000D03*
X545400D03*
X550400Y306500D03*
X563100Y198000D03*
X558900D03*
X554600Y264000D03*
Y259500D03*
X554400Y272100D03*
X554600Y277000D03*
Y281500D03*
X554400Y292250D03*
X554600Y302000D03*
Y306500D03*
X552900Y407000D03*
X557100D03*
Y411500D03*
X552900D03*
X576200Y390700D03*
X572000D03*
X576200Y385700D03*
X572000D03*
X576900Y407500D03*
X581100D03*
Y412000D03*
X576900D03*
X599400Y261500D03*
X603600D03*
X599400Y279000D03*
X603600D03*
X637900Y96500D03*
Y102000D03*
Y108000D03*
X642100Y96500D03*
Y102000D03*
Y108000D03*
G54D26*
X183661Y13781D03*
X187598D03*
X199409D03*
X195472D03*
X191535D03*
X215157D03*
X211220D03*
X219094D03*
X207283D03*
X203346D03*
X234842D03*
X230905D03*
X238779D03*
X246653D03*
X250590D03*
X254527D03*
X242716D03*
X258464D03*
X266338D03*
X270275D03*
X262401D03*
X282086D03*
X286023D03*
X289960D03*
X278149D03*
X274212D03*
X297834D03*
X301771D03*
X305708D03*
X293897D03*
X309645D03*
G54D35*
X393098Y152847D03*
X389160Y148910D03*
X393098D03*
Y164658D03*
Y176470D03*
Y172532D03*
Y184343D03*
Y200091D03*
X393097Y204028D03*
X393098Y207964D03*
Y211902D03*
X389160Y215839D03*
X393098D03*
X397035Y144973D03*
X404910Y141036D03*
Y137098D03*
X400973Y144972D03*
X397036Y152847D03*
X400973Y160720D03*
Y164658D03*
X397035Y148911D03*
X397036Y164658D03*
X400973Y148910D03*
X408847Y160721D03*
X404910Y164659D03*
Y160721D03*
X408847Y156784D03*
X400973Y156785D03*
Y152847D03*
X404909Y148910D03*
X408847D03*
X400972Y180406D03*
X404910D03*
X404909Y168595D03*
X408847D03*
X404910Y196155D03*
Y192217D03*
X397035D03*
X400973D03*
X408846Y196154D03*
X397036Y184343D03*
Y200091D03*
X397035Y204028D03*
X420658Y144973D03*
Y141035D03*
Y160720D03*
Y164658D03*
X412783Y148910D03*
X416721D03*
X412783Y152847D03*
X416721D03*
X420658Y148909D03*
Y152847D03*
X424595Y164659D03*
Y160721D03*
X416721Y164658D03*
X424596Y156784D03*
X420658D03*
X416721Y156783D03*
Y160721D03*
X412784Y164657D03*
X412785Y160721D03*
Y156784D03*
X420657Y180406D03*
X424595D03*
X416721Y168596D03*
X420657Y168595D03*
X424595D03*
X412784D03*
X420658Y188281D03*
Y184343D03*
X416721Y196154D03*
X412784D03*
X424595Y215840D03*
Y211902D03*
X416721Y200092D03*
X416722Y204028D03*
X412784D03*
X440343Y137099D03*
Y133161D03*
X444280Y141035D03*
Y144973D03*
X436406D03*
X430900Y144531D03*
X440343Y156783D03*
Y160721D03*
X444280Y164658D03*
Y160722D03*
Y156784D03*
X440343Y164657D03*
X436406Y164659D03*
Y160721D03*
Y148911D03*
Y152846D03*
Y156784D03*
X430900Y148469D03*
X444280Y168595D03*
X440343D03*
X440344Y180406D03*
X436406D03*
X444280Y180405D03*
X440342Y192217D03*
X444280D03*
X431006Y193718D03*
Y189780D03*
X444280Y184343D03*
X440343Y215839D03*
Y219777D03*
X463965Y129224D03*
X460027D03*
X452154Y141035D03*
Y137097D03*
X456090Y141035D03*
X460028D03*
X452155Y144973D03*
X448217D03*
X460028Y156785D03*
Y152847D03*
X452154Y164657D03*
X448217Y156783D03*
Y160721D03*
X448218Y164658D03*
X463964Y156784D03*
X448218Y168595D03*
X452154D03*
X460027D03*
X463965D03*
Y180406D03*
X452154D03*
X448217Y180405D03*
X463966Y196154D03*
X460028D03*
X463966Y192217D03*
X460028D03*
X463965Y188281D03*
Y184343D03*
X448216Y196154D03*
Y192216D03*
X452154Y184344D03*
X448217Y184343D03*
X456090D03*
X460028D03*
X460029Y188280D03*
X456091D03*
X448216Y207965D03*
X452154D03*
X476666Y138867D03*
Y142805D03*
X467902Y156784D03*
X467903Y180406D03*
X467901Y168595D03*
X471839D03*
X467902Y188281D03*
Y184343D03*
Y215840D03*
Y211902D03*
X475777Y200091D03*
X471839D03*
Y215840D03*
Y211902D03*
X471840Y207965D03*
X467902D03*
G54D54*
G01X384384Y169275D02*
X384474D01*
X384869Y168880D01*
X395867D01*
G03X396681Y169694I0J814D01*
G01Y169793D01*
G03X395910Y170564I-771J0D01*
G01X395067D01*
G01X384384Y167775D02*
X384474D01*
X384869Y168170D01*
X395867D01*
G03X397391Y169694I0J1524D01*
G01Y169793D01*
G02X398162Y170564I771J0D01*
G01X399005D01*
G01X383720Y165395D02*
X383810D01*
X384205Y165000D01*
X388081D01*
G03X388550Y165194I0J664D01*
G01X388613Y165257D01*
G03X388807Y165726I-470J469D01*
G01Y166267D01*
G03X388447Y166627I-360J0D01*
G01X387193D01*
G01X383720Y163895D02*
X383810D01*
X384205Y164290D01*
X388081D01*
G03X389053Y164691I2J1375D01*
G01X389117Y164755D01*
G03X389517Y165726I-974J969D01*
G01Y165927D01*
G02X390217Y166627I700J0D01*
G01X391130D01*
G01X384816Y161475D02*
X384906D01*
X385301Y161080D01*
X395900D01*
G03X396681Y161861I0J781D01*
G01Y161941D01*
G03X395932Y162690I-749J0D01*
G01X395067D01*
G01X384816Y159975D02*
X384906D01*
X385301Y160370D01*
X395900D01*
G03X397391Y161861I0J1491D01*
G01Y161919D01*
G02X398162Y162690I771J0D01*
G01X399005D01*
G01X382969Y156033D02*
X383032Y156096D01*
X383441D01*
G03X383695Y156201I0J360D01*
G01X383956Y156462D01*
G02X385700Y157183I1742J-1745D01*
G01X388066D01*
G03X388807Y157924I0J741D01*
G01Y158004D01*
G03X388058Y158753I-749J0D01*
G01X387193D01*
G01X384030Y154972D02*
X384093Y155035D01*
Y155444D01*
G02X384198Y155698I360J0D01*
G01X384459Y155959D01*
G02X385700Y156473I1241J-1241D01*
G01X388066D01*
G03X389517Y157924I0J1451D01*
G01Y157982D01*
G02X390288Y158753I771J0D01*
G01X391130D01*
G54D45*
X651582Y197244D03*
Y224804D03*
G54D18*
X24807Y335985D03*
Y347245D03*
X43705Y331655D03*
Y351576D03*
G54D27*
X179724Y15731D03*
G54D36*
X398250Y232500D03*
X408750D03*
G54D55*
G01X12500Y91000D02*
X13000D01*
X16500Y94500D01*
X29500D01*
X44000Y109000D01*
X57076D01*
X61106Y113030D01*
X63770D01*
X65240Y114500D01*
X67500D01*
G01X68000Y119000D02*
X67661D01*
X63161Y114500D01*
X59576D01*
X57841Y116235D01*
X55159D01*
X54424Y115500D01*
X43000D01*
X28500Y101000D01*
X12500D01*
G01Y106000D02*
X28500D01*
X39470Y116970D01*
X53815D01*
X54550Y117705D01*
X60044D01*
X61574Y119235D01*
X64736D01*
X66736Y121235D01*
X71265D01*
X73500Y119000D01*
G01X98500Y159000D02*
X100500Y157000D01*
Y140839D01*
X97426Y137765D01*
X86974D01*
X80209Y144530D01*
X66530D01*
X59308Y137308D01*
X54581D01*
X50735Y141121D01*
Y141841D01*
X49500Y143076D01*
Y148500D01*
X42000Y156000D01*
X30802D01*
X23600Y148798D01*
G01X12500Y204500D02*
X13000D01*
X16500Y208000D01*
X26000D01*
X48000Y186000D01*
Y184576D01*
X48735Y183841D01*
Y183189D01*
X52159Y179765D01*
X54841D01*
X55076Y180000D01*
X61500D01*
X69000Y187500D01*
G01X12500Y214500D02*
X26500D01*
X49500Y191500D01*
X67500D01*
X69000Y193000D01*
G01X12500Y219500D02*
X24000D01*
X49000Y194500D01*
X64999D01*
X69023Y198524D01*
G01X24100Y302500D02*
Y297500D01*
G01Y302500D02*
X27000D01*
X27500Y302000D01*
X28500D01*
G01X24100Y292500D02*
Y287500D01*
G01Y292500D02*
X24500D01*
X28000Y296000D01*
Y296500D01*
G01X44500Y73500D02*
X47500D01*
X51300Y69700D01*
X53000D01*
G01X89000Y110500D02*
X81000Y118500D01*
X79000D01*
X74795Y122705D01*
X66127D01*
X64422Y121000D01*
X61000D01*
X59175Y119175D01*
X53941D01*
X53206Y118440D01*
X45560D01*
X39265Y124735D01*
Y130265D01*
X41409Y132409D01*
Y132591D01*
G01X41500Y127500D02*
Y125000D01*
X46590Y119910D01*
X52597D01*
X53332Y120645D01*
X57645D01*
X59500Y122500D01*
X63843D01*
X65518Y124175D01*
X75404D01*
X79579Y120000D01*
X87000D01*
G01X98500Y165500D02*
X99500D01*
X103470Y161530D01*
Y138392D01*
X98578Y133500D01*
X76579D01*
X75609Y134470D01*
X62815D01*
X61845Y133500D01*
X54080D01*
X53110Y134470D01*
X48191D01*
X47161Y135500D01*
X43500D01*
X41500Y137500D01*
Y145001D01*
X43835Y147336D01*
Y149724D01*
X42526Y151033D01*
X39335D01*
X37100Y148798D01*
G01X28100D02*
X31805Y152503D01*
X43135D01*
X45305Y150333D01*
Y146500D01*
X43000Y144195D01*
Y139000D01*
X45000Y137000D01*
X46999D01*
X47029Y136970D01*
X47770D01*
X48800Y135940D01*
X53719D01*
X54159Y135500D01*
X61766D01*
X62206Y135940D01*
X76218D01*
X77188Y134970D01*
X97969D01*
X102000Y139001D01*
Y160501D01*
X100266Y162235D01*
X97159D01*
X94924Y160000D01*
X93500D01*
X91000Y162500D01*
Y172000D01*
X92000Y173000D01*
G01X96500Y235500D02*
X98935Y233065D01*
Y225435D01*
X95500Y222000D01*
X81000D01*
X76500Y217500D01*
X61500D01*
X60000Y216000D01*
X55499D01*
X54499Y217000D01*
X48569D01*
X45000Y213431D01*
Y213000D01*
G01X28500Y302000D02*
X29000D01*
X30720Y300280D01*
X36950D01*
G01X28000Y296500D02*
X28500D01*
X29720Y297720D01*
X36950D01*
G01X29000Y287100D02*
X33500D01*
G01X29000D02*
Y291500D01*
G01D02*
Y292000D01*
X32160Y295160D01*
X36950D01*
G01X55500Y59000D02*
Y60000D01*
X55708Y60208D01*
Y60228D01*
X57700Y62220D01*
Y65500D01*
G01X64400Y70000D02*
X59900Y65500D01*
X57700D01*
G01X50500Y60228D02*
X51772D01*
X53000Y61456D01*
Y65500D01*
G01X53500Y88400D02*
Y87000D01*
X57000Y83500D01*
G01X63500Y84500D02*
X60750Y87250D01*
Y92250D01*
X65500Y97000D01*
Y102500D01*
X71267Y108267D01*
X83732D01*
X89732Y102267D01*
X96268D01*
X97733Y103732D01*
Y127312D01*
X105000Y134579D01*
Y163576D01*
X99841Y168735D01*
X97159D01*
X94500Y166076D01*
Y163000D01*
G01X57500Y101500D02*
X55500Y99500D01*
Y94600D01*
X53500Y92600D01*
G01X90500Y105000D02*
X79765Y115735D01*
X72159D01*
X68689Y112265D01*
X65452D01*
X64487Y111300D01*
X62300D01*
X51765Y100765D01*
Y96600D01*
G01X93500Y110500D02*
X90500Y113500D01*
Y120500D01*
X88735Y122265D01*
X79761D01*
X76121Y125905D01*
X64801D01*
X63126Y124230D01*
X58230D01*
X56375Y122375D01*
X49125D01*
X48500Y123000D01*
Y128202D01*
X48390Y128312D01*
G01X55922Y140543D02*
Y141478D01*
X53000Y144400D01*
G01X87000Y130000D02*
X78000D01*
X75000Y133000D01*
X63424D01*
X62424Y132000D01*
X53501D01*
X52501Y133000D01*
X46500D01*
G01X95200Y151000D02*
X99000Y147200D01*
Y144000D01*
X97235Y142235D01*
X88826D01*
X87526Y143535D01*
X83965D01*
X81500Y146000D01*
X64500D01*
X62000Y148500D01*
X58839D01*
X57365Y149974D01*
Y159135D01*
X54500Y162000D01*
Y171000D01*
G01X60600Y157000D02*
Y156300D01*
X67400Y149500D01*
G01X48957Y153619D02*
Y152643D01*
X53000Y148600D01*
G01Y204900D02*
Y200500D01*
G01X49600Y213455D02*
Y210064D01*
X50564Y209100D01*
X53000D01*
G01X95700Y227500D02*
X92700Y224500D01*
X81001D01*
X75731Y219230D01*
X64770D01*
X57500Y226500D01*
G01X55200Y253500D02*
X53000Y255700D01*
Y258400D01*
G01Y262600D02*
X51880Y263720D01*
Y271080D01*
X52800Y272000D01*
G01X100500Y284730D02*
X98995Y286235D01*
X91265D01*
X87500Y290000D01*
X87121D01*
X86934Y290187D01*
X84666D01*
X84479Y290000D01*
X83970D01*
X83000Y289030D01*
Y285500D01*
X75500Y278000D01*
X52500D01*
G01X64500Y296750D02*
X62860D01*
X59330Y300280D01*
X55050D01*
G01X66000Y301400D02*
X62900D01*
X61800Y302500D01*
G01X55050Y302840D02*
Y307240D01*
X55520Y307710D01*
X58660D01*
X59130Y307240D01*
Y305170D01*
X61800Y302500D01*
G01X55050Y297720D02*
X58809D01*
X63600Y292929D01*
Y291500D01*
G01X66000Y305600D02*
X64600Y307000D01*
X62000D01*
G01X64400Y70000D02*
X63500Y70900D01*
Y79000D01*
X67000Y82500D01*
Y86500D01*
X63500Y90000D01*
Y92500D01*
X67000Y96000D01*
Y101500D01*
X71885Y106385D01*
X83115D01*
X89000Y100500D01*
X97000D01*
X99500Y103000D01*
Y127000D01*
X106470Y133970D01*
Y164200D01*
X98670Y172000D01*
X97500D01*
G01X79900Y71100D02*
X80900Y70100D01*
Y66500D01*
G01X75500Y62000D02*
X76500D01*
X80900Y66400D01*
Y66500D01*
G01X78500Y82250D02*
X78050D01*
X74400Y85900D01*
X72100D01*
G01X71500Y77000D02*
X72100Y77600D01*
Y81700D01*
G01X83300Y95300D02*
X78800D01*
G01X79000Y100500D02*
X78800Y100300D01*
Y95300D01*
G01X74300D02*
X69800D01*
G01X74000Y100500D02*
X74300Y100200D01*
Y95300D01*
G01X91000Y181500D02*
X89500Y183000D01*
X82000D01*
X67500Y168500D01*
Y165800D01*
X64000Y162300D01*
Y157900D01*
X67500Y154400D01*
G01X88250Y177250D02*
X85265Y180235D01*
X82574D01*
X69230Y166891D01*
Y165083D01*
X67600Y163453D01*
Y159900D01*
G01X71600Y149500D02*
Y154300D01*
X71700Y154400D01*
G01X80800Y154900D02*
X76570D01*
X76100Y154430D01*
Y154400D01*
G01D02*
X71700D01*
G01X80800Y159400D02*
X77600D01*
X75950Y161050D01*
Y164050D01*
G01X71800Y159900D02*
X75950Y164050D01*
G01D02*
Y164200D01*
G01X99000Y197500D02*
X94500Y202000D01*
X90000D01*
X86000Y206000D01*
X63000D01*
G01X99000Y201500D02*
X96500Y204000D01*
X91500D01*
X85000Y210500D01*
X63000D01*
G01X98500Y218500D02*
X96500D01*
X90500Y212500D01*
X65500D01*
X63000Y215000D01*
G01X76000Y244400D02*
X71500D01*
G01X79600Y248900D02*
X76800D01*
X76000Y248100D01*
Y244400D01*
G01X332500Y306500D02*
X327000Y312000D01*
X308500D01*
X301000Y304500D01*
X289000D01*
X264000Y329500D01*
X241983D01*
X235650Y323167D01*
Y283415D01*
X226740Y274505D01*
X206005D01*
X179500Y248000D01*
X97523D01*
X91658Y253865D01*
X84565D01*
X79600Y248900D01*
G01X79500Y234500D02*
Y234949D01*
X76000Y238449D01*
Y240200D01*
G01X226500Y334000D02*
X225500Y333000D01*
Y321500D01*
X220400Y316400D01*
X205000D01*
X199500Y310900D01*
Y292000D01*
X192230Y284730D01*
X167270D01*
X162580Y289420D01*
X140580D01*
X134730Y295270D01*
X92730D01*
X89000Y299000D01*
X84500D01*
X79500Y294000D01*
X71000D01*
X69900Y295100D01*
Y296500D01*
X64750D01*
X64500Y296750D01*
G01X63600Y291500D02*
X69900D01*
G01X297000Y310500D02*
X288098D01*
X265548Y333050D01*
X240639D01*
X232190Y324601D01*
Y285689D01*
X226001Y279500D01*
X164447D01*
X159717Y284230D01*
X127770D01*
X119000Y293000D01*
X102000D01*
X96965Y287965D01*
X92035D01*
X88000Y292000D01*
X82000D01*
X79000Y289000D01*
X70370D01*
X69900Y289470D01*
Y291500D01*
G01X66000Y305600D02*
X74900D01*
X77000Y303500D01*
X81500D01*
X85000Y307000D01*
X91500D01*
X101500Y297000D01*
X135500D01*
X141000Y291500D01*
X164000D01*
X169040Y286460D01*
X189960D01*
X197000Y293500D01*
Y311357D01*
X204143Y318500D01*
X219530D01*
X222500Y321470D01*
Y324500D01*
G01X70400Y315500D02*
Y320000D01*
G01D02*
X67500D01*
X66000Y318500D01*
G01X74600Y315500D02*
X79000D01*
G01X70400Y324500D02*
X69400Y323500D01*
X66000D01*
G01X79500Y348500D02*
X80805D01*
X81305Y349000D01*
X85000D01*
X86000Y350000D01*
X86900D01*
G01X403000Y418500D02*
X399000Y422500D01*
X389500D01*
X363500Y396500D01*
Y382400D01*
X354600Y373500D01*
X329999D01*
X327499Y371000D01*
X324421D01*
X320421Y367000D01*
X290324D01*
X284957Y372367D01*
Y424043D01*
X279000Y430000D01*
X81600D01*
X70600Y419000D01*
X70500D01*
G01X398000Y418500D02*
X395500Y421000D01*
X390499D01*
X365500Y396001D01*
Y381300D01*
X356200Y372000D01*
X331000D01*
X328500Y369500D01*
X325000D01*
X321000Y365500D01*
X289322D01*
X283188Y371634D01*
Y422812D01*
X277500Y428500D01*
X83000D01*
X75580Y421080D01*
Y419004D01*
G01X84200Y75000D02*
X83900Y75300D01*
X79900D01*
G01Y71100D02*
X84600D01*
X84700Y71000D01*
G01X87800Y95300D02*
X90700D01*
X94000Y92000D01*
X103500D01*
X111630Y83870D01*
Y83200D01*
X115830Y79000D01*
X134130D01*
X135100Y78030D01*
Y75300D01*
G01X84000Y100500D02*
X86200D01*
X87800Y98900D01*
Y95300D01*
G01X90500Y144500D02*
X89500Y145500D01*
X86685D01*
X84600Y147585D01*
Y150000D01*
G01X85000Y159400D02*
X88409D01*
X91100Y156709D01*
Y151400D01*
X92000Y150500D01*
Y149000D01*
X95500Y145500D01*
G01X80400Y150000D02*
X80800Y150400D01*
Y154900D01*
G01Y163900D02*
Y159400D01*
G01Y168400D02*
Y163900D01*
G01X83500Y173000D02*
X85000Y171500D01*
Y168400D01*
G01X82500Y230500D02*
X83000Y231000D01*
Y236024D01*
X80500Y238524D01*
Y240200D01*
G01Y244400D02*
X85000D01*
G01X84600Y248900D02*
X85000Y248500D01*
Y244400D01*
G01X84600Y248900D02*
X87835Y252135D01*
X90941D01*
X97076Y246000D01*
X179947D01*
X206722Y272775D01*
X227457D01*
X237380Y282698D01*
Y322450D01*
X242700Y327770D01*
X263283D01*
X288553Y302500D01*
X302500D01*
X310000Y310000D01*
X318526D01*
X318996Y309530D01*
Y307470D01*
X319466Y307000D01*
X320996D01*
X321466Y307470D01*
Y309530D01*
X321936Y310000D01*
X324500D01*
X328000Y306500D01*
G01X89600Y244400D02*
Y248900D01*
G01X126067Y264043D02*
X116611D01*
X97554Y283100D01*
X90800D01*
G01Y278900D02*
X95900D01*
G01X85800D02*
X82600Y275700D01*
Y273300D01*
X82500Y273200D01*
G01X101500Y341000D02*
Y341500D01*
X95000Y348000D01*
X93100D01*
X91100Y350000D01*
G01Y341000D02*
X97500D01*
G01X95100Y351900D02*
X95000Y352000D01*
Y356400D01*
G01X83000Y352500D02*
X82583Y352917D01*
Y353583D01*
X84300Y355300D01*
X88200D01*
G01X86900Y345500D02*
Y350000D01*
G01X83000Y344500D02*
Y343999D01*
X85999Y341000D01*
X86900D01*
G01X95000Y360600D02*
X91970D01*
X91500Y360130D01*
Y359500D01*
G01X83500Y360000D02*
X84000D01*
X84500Y359500D01*
X88200D01*
G01X90000Y420500D02*
X90583D01*
X93583Y423500D01*
X236543D01*
X238500Y421543D01*
Y389000D01*
X250000Y377500D01*
X269579D01*
X287784Y359295D01*
X326535D01*
X328705Y361465D01*
Y364626D01*
X329109Y365030D01*
X330267D01*
X332737Y367500D01*
X359280D01*
X371000Y379220D01*
Y394763D01*
X390237Y414000D01*
X405501D01*
X413001Y421500D01*
X418001D01*
X420501Y424000D01*
X422337D01*
G01X85500Y420500D02*
Y423924D01*
X87076Y425500D01*
X238500D01*
X241000Y423000D01*
Y389000D01*
X251000Y379000D01*
X270501D01*
X288736Y360765D01*
X325926D01*
X327235Y362074D01*
Y365235D01*
X328500Y366500D01*
X329658D01*
X332218Y369060D01*
X358060D01*
X369000Y380000D01*
Y394842D01*
X390158Y416000D01*
X404500D01*
X412500Y424000D01*
X416800D01*
G01X393000Y418500D02*
X390501D01*
X367500Y395499D01*
Y381221D01*
X356809Y370530D01*
X331609D01*
X329109Y368030D01*
X326030D01*
X321500Y363500D01*
X288500D01*
X280500Y371500D01*
Y422000D01*
X275500Y427000D01*
X84000D01*
X80500Y423500D01*
Y420500D01*
G01X108000Y71800D02*
X111660D01*
X112880Y73020D01*
G01X117370Y70860D02*
X115040D01*
X112880Y73020D01*
G01X375500Y350500D02*
X365035Y340035D01*
Y318035D01*
X356000Y309000D01*
X354576D01*
X352341Y311235D01*
X349659D01*
X348159Y309735D01*
X344659D01*
X342924Y308000D01*
X334161D01*
X328161Y314000D01*
X308000D01*
X300500Y306500D01*
X289650D01*
X264830Y331320D01*
X241356D01*
X233920Y323884D01*
Y284420D01*
X227000Y277500D01*
X164000D01*
X159000Y282500D01*
X102730D01*
X100500Y284730D01*
G01X103000Y351500D02*
X104000Y352500D01*
Y356400D01*
G01Y360600D02*
X99500D01*
G01Y370000D02*
Y360600D01*
G01X105500Y368900D02*
X102600D01*
X101500Y370000D01*
X99500D01*
G01X104500Y377000D02*
X104735Y376765D01*
X127574D01*
X131074Y373265D01*
X134765D01*
X136500Y375000D01*
X142000D01*
X143500Y373500D01*
Y370000D01*
X145500Y368000D01*
X146500D01*
X148000Y366500D01*
X152000D01*
X156000Y362500D01*
Y336500D01*
X160500Y332000D01*
Y298900D01*
X156600Y295000D01*
G01X414000Y419000D02*
X407500Y412500D01*
X390974D01*
X372470Y393996D01*
Y378611D01*
X359859Y366000D01*
X333999D01*
X330175Y362176D01*
Y360856D01*
X327144Y357825D01*
X287175D01*
X270000Y375000D01*
X249999D01*
X236000Y388999D01*
Y420030D01*
X234530Y421500D01*
X107500D01*
X103500Y417500D01*
X100500D01*
X98000Y420000D01*
G01X130870Y70800D02*
X127070Y67000D01*
X126000D01*
G01Y62000D02*
X127050D01*
X130850Y65800D01*
G01X126000Y62000D02*
X125450D01*
X121580Y65870D01*
G01X121570Y70860D02*
X124860D01*
X126000Y72000D01*
G01X131500Y290500D02*
Y288500D01*
X134040Y285960D01*
X160434D01*
X165164Y281230D01*
X221477D01*
X229730Y289483D01*
Y329341D01*
X237739Y337350D01*
X266142D01*
X278992Y324500D01*
X291730D01*
X292200Y324970D01*
Y328500D01*
X293200Y329500D01*
G01X135000Y312000D02*
X132400Y309400D01*
X128000D01*
G01X126000Y318000D02*
X128000Y316000D01*
Y313600D01*
G01X129500Y328000D02*
X133900D01*
G01X119000Y352000D02*
X117500Y353500D01*
Y356400D01*
G01X145900Y75200D02*
X146320Y74780D01*
Y73450D01*
X145850Y72980D01*
X144330D01*
X143860Y73450D01*
Y74010D01*
X143320Y74550D01*
X141130D01*
X140640Y74060D01*
Y72800D01*
X138640Y70800D01*
Y69510D01*
X137460Y68330D01*
X135540D01*
X135070Y68800D01*
Y70800D01*
G01X135050Y65800D02*
X142841D01*
X145235Y68194D01*
Y69226D01*
X151200Y75191D01*
G01X136000Y290500D02*
X138810Y287690D01*
X161151D01*
X165841Y283000D01*
X220330D01*
X228000Y290670D01*
Y330652D01*
X236848Y339500D01*
X266439D01*
X269755Y336184D01*
X270419D01*
X271684Y337450D01*
X272348D01*
X273431Y336367D01*
Y335703D01*
X272166Y334437D01*
Y333773D01*
X273249Y332690D01*
X273912D01*
X274829Y333607D01*
X275493D01*
X276576Y332524D01*
Y331860D01*
X275660Y330944D01*
Y330279D01*
X279439Y326500D01*
X289830D01*
X290300Y326970D01*
Y329400D01*
X289600Y330100D01*
G01X146000Y334000D02*
X140000Y328000D01*
X138100D01*
G01X133900Y323500D02*
Y328000D01*
G01X147700Y390100D02*
Y394600D01*
G01X153500Y390500D02*
X152900Y389900D01*
X147900D01*
X147700Y390100D01*
G01X146700Y385100D02*
X149900D01*
X151100Y386300D01*
G01X138500Y387500D02*
X139500Y388500D01*
X141900D01*
X143500Y390100D01*
G01X152100Y300000D02*
X155700D01*
X156800Y301100D01*
G01X154000Y377600D02*
Y382100D01*
X153900Y382200D01*
G01X153500Y390500D02*
X154400Y389600D01*
Y382700D01*
X153900Y382200D01*
G01X186460Y60220D02*
Y49156D01*
X179724Y42420D01*
Y15731D01*
G01X186460Y64420D02*
Y72050D01*
X180620Y77890D01*
G01X188500Y293900D02*
X180200D01*
X179500Y294600D01*
G01X192400Y45786D02*
X194270Y43916D01*
Y34330D01*
X195472Y33128D01*
Y13781D01*
G01X198000Y49500D02*
X196000Y47500D01*
Y35048D01*
X197202Y33846D01*
Y26207D01*
X199409Y24000D01*
Y13781D01*
G01X201370Y43000D02*
Y33370D01*
X199500Y31500D01*
Y26846D01*
X203346Y23000D01*
Y13781D01*
G01X186460Y60220D02*
X188430D01*
X188900Y59750D01*
Y54960D01*
G01X207880Y78740D02*
X200240D01*
X199732Y78232D01*
Y75161D01*
X194469Y69898D01*
Y58620D01*
X191765Y55916D01*
Y46421D01*
X192400Y45786D01*
G01X203000Y75000D02*
X199469Y71469D01*
Y50969D01*
X198000Y49500D01*
G01X208160Y73990D02*
Y65920D01*
X205060Y62820D01*
Y46690D01*
X201370Y43000D01*
G01X422627Y194185D02*
X420542Y192100D01*
X417800D01*
X417000Y191300D01*
Y185800D01*
X415800Y184600D01*
X409500D01*
X408780Y183880D01*
Y177780D01*
X407660Y176660D01*
X398340D01*
X397000Y178000D01*
Y179500D01*
X396133Y180367D01*
X380567D01*
X377434Y183500D01*
X366200D01*
X354400Y171700D01*
X329701D01*
X315001Y157000D01*
X269710D01*
X196497Y83787D01*
Y76502D01*
G01X196950Y348800D02*
X205000D01*
G01Y353800D02*
X196950D01*
G01X210500Y345100D02*
X207695D01*
X207225Y344630D01*
Y342070D01*
X206755Y341600D01*
X205225D01*
X204755Y342070D01*
Y344630D01*
X204285Y345100D01*
X203000D01*
X201700Y343800D01*
X196950D01*
G01Y338800D02*
X203700D01*
X205000Y337500D01*
G01X229582Y48918D02*
X224664Y44000D01*
X223000D01*
X219094Y40094D01*
Y13781D01*
G01X207283D02*
Y24217D01*
X204500Y27000D01*
Y42182D01*
X208295Y45977D01*
Y52500D01*
G01D02*
Y56855D01*
X210060Y58620D01*
Y67560D01*
X214810Y72310D01*
Y78810D01*
G01X217300Y297300D02*
Y300500D01*
X218500Y301700D01*
G01X212800Y297300D02*
Y301000D01*
X213500Y301700D01*
G01X208500D02*
X208300Y301500D01*
Y297300D01*
G01X210500Y340900D02*
Y336100D01*
X210400Y336000D01*
G01D02*
X206500D01*
X205000Y337500D01*
G01Y348800D02*
X209200D01*
X210400Y350000D01*
G01Y355000D02*
X209200Y353800D01*
X205000D01*
G01X210500Y345100D02*
X213700D01*
X215000Y343800D01*
G01X244000Y219300D02*
Y195000D01*
X266000Y173000D01*
X288447D01*
X293217Y177770D01*
X342730D01*
X346500Y174000D01*
G01X249499Y204000D02*
Y194000D01*
X268769Y174730D01*
X287730D01*
X292500Y179500D01*
X342500D01*
X344500Y181500D01*
G01X246559Y219300D02*
Y206940D01*
X249499Y204000D01*
G01X259000Y230600D02*
X254000D01*
G01X241441Y228700D02*
Y226059D01*
X242000Y225500D01*
X248500D01*
X250500Y227500D01*
Y230000D01*
X251100Y230600D01*
X254000D01*
G01Y226400D02*
Y221600D01*
G01X246559Y219300D02*
Y221559D01*
X247500Y222500D01*
X249500D01*
X250400Y221600D01*
X254000D01*
G01X255400Y290100D02*
Y280300D01*
X252000Y276900D01*
Y249700D01*
X255100Y246600D01*
Y237500D01*
G01X305350Y221700D02*
X312600D01*
X315500Y218800D01*
Y192000D01*
X305000Y181500D01*
X291500D01*
X286500Y176500D01*
X273000D01*
X266500Y183000D01*
Y206500D01*
G01D02*
X261000Y212000D01*
Y221839D01*
X265209Y226048D01*
Y230599D01*
X265210Y230600D01*
G01X265260Y219350D02*
Y215760D01*
X264500Y215000D01*
Y214000D01*
G01X265260Y230650D02*
X265210Y230600D01*
G01D02*
X259000D01*
G01X265260Y219350D02*
Y222760D01*
X268000Y225500D01*
Y236000D01*
X266500Y237500D01*
X264100D01*
G01X259900D02*
X255100D01*
G01X284500Y222200D02*
Y227200D01*
X285000Y227700D01*
G01X295000Y213000D02*
X289500Y218500D01*
Y221030D01*
X288330Y222200D01*
X284500D01*
G01X298284Y175184D02*
X300816D01*
X306500Y169500D01*
G01X305850Y231500D02*
X302500D01*
X301365Y230365D01*
Y216268D01*
X299597Y214500D01*
X296500D01*
X295000Y213000D01*
G01X291000Y229900D02*
X293100Y227800D01*
X297150D01*
G01X296650Y218000D02*
X295500D01*
X292500Y221000D01*
Y222850D01*
G01X297150Y227800D02*
Y225150D01*
X296000Y224000D01*
X293650D01*
X292500Y222850D01*
G01X302600Y335000D02*
Y330500D01*
G01Y335000D02*
X297800D01*
X297700Y335100D01*
G01X450000Y416500D02*
X445500Y421000D01*
X420000D01*
X409500Y410500D01*
X393500D01*
X374230Y391230D01*
Y371730D01*
X356460Y353960D01*
X323277D01*
X316047Y346730D01*
X296283D01*
X290370Y340817D01*
Y330870D01*
X289600Y330100D01*
G01X293200Y329500D02*
X292100Y330600D01*
Y340100D01*
X297000Y345000D01*
X316764D01*
X323994Y352230D01*
X357730D01*
X376000Y370500D01*
Y390553D01*
X393447Y408000D01*
X410000D01*
X421000Y419000D01*
X444520D01*
X446135Y417385D01*
Y415365D01*
X450000Y411500D01*
G01X478000Y78000D02*
X469000Y69000D01*
X376999D01*
X354999Y91000D01*
X344500D01*
X340500Y87000D01*
G01X519500Y81500D02*
X513000D01*
X492267Y60767D01*
X370732D01*
X353732Y77767D01*
X342732D01*
X337500Y82999D01*
Y88500D01*
X345000Y96000D01*
X360500D01*
X364000Y99500D01*
Y118500D01*
X362000Y120500D01*
Y123500D01*
G01X519500Y75500D02*
X509500D01*
X493000Y59000D01*
X370000D01*
X353000Y76000D01*
X342000D01*
X335000Y83000D01*
Y89501D01*
X343266Y97767D01*
X359768D01*
X362233Y100232D01*
Y110787D01*
X359500Y113520D01*
Y125500D01*
X362000Y128000D01*
G01X332900Y221000D02*
Y218476D01*
X329315Y214891D01*
Y212209D01*
X331209Y210315D01*
X333891D01*
X335441Y208765D01*
X345341D01*
X349165Y212589D01*
Y227336D01*
X346001Y230500D01*
X341000D01*
X338500Y233000D01*
Y238000D01*
X341500Y241000D01*
X344914D01*
X363500Y259586D01*
Y266339D01*
X362765Y267074D01*
Y274225D01*
X357000Y279990D01*
Y295500D01*
G01X332900Y221000D02*
Y225500D01*
G01X346100D02*
X345935Y225665D01*
Y228030D01*
X345465Y228500D01*
X340499D01*
X336500Y232499D01*
Y240762D01*
X338738Y243000D01*
X344467D01*
X347975Y246508D01*
Y247172D01*
X342906Y252241D01*
Y252905D01*
X343989Y253988D01*
X344653D01*
X349722Y248919D01*
X350386D01*
X351469Y250002D01*
Y250666D01*
X346400Y255735D01*
Y256399D01*
X347483Y257482D01*
X348147D01*
X353216Y252413D01*
X353880D01*
X354963Y253496D01*
Y254160D01*
X352894Y256229D01*
Y256893D01*
X353977Y257976D01*
X354641D01*
X356710Y255907D01*
X357374D01*
X361770Y260303D01*
Y265622D01*
X361035Y266357D01*
Y273508D01*
X352665Y281878D01*
Y293165D01*
X353500Y294000D01*
Y299800D01*
X356000Y302300D01*
G01X337100Y221000D02*
X344000Y214100D01*
Y212000D01*
G01X332600Y246600D02*
Y248200D01*
X333500Y249100D01*
Y251100D01*
G01X338500Y259000D02*
Y256700D01*
X337100Y255300D01*
X333500D01*
G01X335000Y286400D02*
Y282650D01*
X334350Y282000D01*
G01X339500Y290600D02*
X335000D01*
G01X324000Y301000D02*
X326765Y298235D01*
X339295D01*
X340500Y297030D01*
Y294500D01*
X339500Y293500D01*
Y290600D01*
G01X348500Y286400D02*
X349000D01*
X350935Y288335D01*
Y294274D01*
X351500Y294839D01*
Y297500D01*
X350000Y299000D01*
X340977D01*
X338477Y301500D01*
X332000D01*
G01X329800Y320500D02*
X336525D01*
G01X329800D02*
Y325000D01*
G01X336525Y325500D02*
X333800D01*
X329800Y329500D01*
G01Y334000D02*
Y329500D01*
G01X337000Y344000D02*
Y330975D01*
X336525Y330500D01*
G01X325600Y347500D02*
Y349599D01*
X326501Y350500D01*
X360252D01*
X360876Y349876D01*
X361124D01*
G01X329800Y347500D02*
Y343000D01*
G01D02*
Y338500D01*
G01Y347500D02*
X333500D01*
X337000Y344000D01*
G01X482000Y83500D02*
Y78000D01*
X477803Y73803D01*
Y73139D01*
X478459Y72483D01*
Y71819D01*
X477376Y70736D01*
X476712D01*
X476056Y71392D01*
X475392D01*
X474309Y70309D01*
Y69645D01*
X474770Y69184D01*
Y68520D01*
X473687Y67437D01*
X473023D01*
X472562Y67898D01*
X471898D01*
X471000Y67000D01*
X376500D01*
X355000Y88500D01*
X347000D01*
X345500Y87000D01*
G01X533000Y95000D02*
X528500Y90500D01*
X513000D01*
X485500Y63000D01*
X373500D01*
X354000Y82500D01*
G01X533000Y99500D02*
X525730Y92230D01*
X512283D01*
X511553Y91500D01*
X511500D01*
X485000Y65000D01*
X375000D01*
X355000Y85000D01*
X351500D01*
X349000Y82500D01*
G01X346100Y225500D02*
Y221000D01*
G01X345930Y217000D02*
X344930Y218000D01*
X343500D01*
X341900Y219600D01*
Y221000D01*
G01X347000Y233400D02*
X350843D01*
X351000Y233243D01*
G01X347000Y237600D02*
X350400D01*
X351000Y237000D01*
G01X344000Y290600D02*
Y295000D01*
G01Y286400D02*
X348500D01*
G01X341500Y338500D02*
X343000Y337000D01*
X346400D01*
G01Y341500D02*
Y337000D01*
G01Y323500D02*
Y328000D01*
G01X341500Y328500D02*
X342000Y328000D01*
X346400D01*
G01X341500Y333500D02*
X342500Y332500D01*
X346400D01*
G01X406610Y353410D02*
X403500Y356520D01*
X395600D01*
X391815Y352735D01*
X374435D01*
X363300Y341600D01*
Y326300D01*
X360500Y323500D01*
X350600D01*
G01X358250Y340050D02*
X356800Y341500D01*
X350600D01*
G01X352200Y403200D02*
X350757D01*
X348279Y405678D01*
G01X352200Y403200D02*
Y407700D01*
G01X348863Y410500D02*
X351400D01*
X353900Y413000D01*
G01D02*
X355500Y414600D01*
Y417500D01*
X355200Y417800D01*
Y419700D01*
G01X374600Y172000D02*
Y178200D01*
G01X386000Y246800D02*
X383261D01*
X381026Y244565D01*
X377936D01*
X377501Y245000D01*
X377500D01*
X375735Y246765D01*
Y249186D01*
X372030Y252891D01*
Y259030D01*
X376203Y263203D01*
X417624D01*
X420891Y266470D01*
X433891D01*
X439391Y271970D01*
X456891D01*
X459391Y274470D01*
X473609D01*
X489470Y258609D01*
Y238109D01*
X493579Y234000D01*
X495499D01*
X513500Y215999D01*
Y215500D01*
G01X380100Y246800D02*
X378201D01*
X377205Y247796D01*
Y249795D01*
X373500Y253500D01*
Y257999D01*
X377234Y261733D01*
X418233D01*
X421500Y265000D01*
X434500D01*
X440000Y270500D01*
X457500D01*
X460000Y273000D01*
X473000D01*
X488000Y258000D01*
Y237500D01*
X493000Y232500D01*
X494500D01*
X509000Y218000D01*
Y215500D01*
G01X421360Y359970D02*
X411490Y350100D01*
X404100D01*
X399700Y354500D01*
X395940D01*
X392273Y350833D01*
X382657D01*
X379324Y347500D01*
X376000D01*
X366765Y338265D01*
Y317735D01*
X375300Y309200D01*
X375500D01*
G01X435143Y306643D02*
X417457D01*
X409835Y314265D01*
X400735D01*
X399000Y316000D01*
X389500D01*
X385500Y320000D01*
X371000D01*
X368765Y322235D01*
Y331265D01*
X370000Y332500D01*
G01X374400D02*
X370000D01*
G01X374400Y341500D02*
Y343400D01*
X376500Y345500D01*
X381900D01*
X383000Y346600D01*
G01X359400Y419700D02*
Y417100D01*
X360500Y416000D01*
X365500D01*
X368000Y418500D01*
X374500D01*
G01X377000Y91700D02*
X381000D01*
X381700Y92400D01*
G01X391900Y251000D02*
Y246800D01*
G01X511500Y206500D02*
X511447D01*
X497217Y220730D01*
X487533D01*
X479263Y229000D01*
X469000D01*
X466230Y231770D01*
Y252717D01*
X464217Y254730D01*
X432783D01*
X430500Y252447D01*
Y241500D01*
X427635Y238635D01*
X413128D01*
X411263Y240500D01*
X396500D01*
X391900Y245100D01*
Y246800D01*
G01X386000Y251000D02*
Y246800D01*
G01X380100Y251000D02*
Y246800D01*
G01X389100Y309200D02*
Y307300D01*
X391600Y304800D01*
G01X389100Y309200D02*
X383500D01*
G01X383000Y323500D02*
X386500D01*
X392000Y318000D01*
X400500D01*
X401263Y318763D01*
X414245D01*
X414715Y318293D01*
Y312270D01*
X415185Y311800D01*
X416715D01*
X417185Y312270D01*
Y318293D01*
X417655Y318763D01*
X419185D01*
X419655Y318293D01*
Y312270D01*
X420125Y311800D01*
X421655D01*
X422125Y312270D01*
Y318293D01*
X422595Y318763D01*
X424125D01*
X424595Y318293D01*
Y312270D01*
X425065Y311800D01*
X426595D01*
X427065Y312270D01*
Y318293D01*
X427535Y318763D01*
X428557D01*
X433000Y314320D01*
G01X378600Y328000D02*
Y332500D01*
G01X383000Y328500D02*
X382500Y328000D01*
X378600D01*
G01Y337000D02*
Y341500D01*
G01X383000Y333500D02*
Y336000D01*
X382000Y337000D01*
X378600D01*
G01Y323500D02*
X383000D01*
G01X388100Y375800D02*
Y381000D01*
G01D02*
X394000D01*
X395000Y382000D01*
G01X397800Y251000D02*
Y246800D01*
G01X513000Y210500D02*
X509526D01*
X497826Y222200D01*
X488142D01*
X479342Y231000D01*
X475500D01*
X467700Y238800D01*
Y253326D01*
X464826Y256200D01*
X432174D01*
X428500Y252526D01*
Y245000D01*
X428470Y244970D01*
Y244891D01*
X428441Y244862D01*
Y241941D01*
X426655Y240155D01*
X417607D01*
X416702Y241060D01*
X412782D01*
X410842Y243000D01*
X399500D01*
X397800Y244700D01*
Y246800D01*
G01X403700Y251000D02*
Y246800D01*
G01X492500Y226000D02*
X491000D01*
X484000Y233000D01*
Y257000D01*
X478000Y263000D01*
X470161D01*
X469426Y262265D01*
X463235D01*
X461000Y264500D01*
X458000D01*
X451170Y257670D01*
X431048D01*
X427000Y253622D01*
Y245500D01*
X426970Y245470D01*
Y244891D01*
X423704Y241625D01*
X418216D01*
X417311Y242530D01*
X413391D01*
X411421Y244500D01*
X408000D01*
X405700Y246800D01*
X403700D01*
G01X409300Y251000D02*
Y246800D01*
G01X497500Y226000D02*
X492500Y231000D01*
X490001D01*
X486000Y235001D01*
Y257500D01*
X476000Y267500D01*
X466500D01*
X465000Y266000D01*
X459000D01*
X458970Y265970D01*
X457391D01*
X450561Y259140D01*
X430396D01*
X425500Y254244D01*
Y246500D01*
X425471Y246471D01*
Y246131D01*
X422435Y243095D01*
X418825D01*
X417920Y244000D01*
X414000D01*
X411200Y246800D01*
X409300D01*
G01X401500Y323900D02*
Y329100D01*
G01D02*
X405900D01*
X408000Y327000D01*
G01X418690Y205996D02*
X420704Y208010D01*
X427510D01*
X429500Y210000D01*
Y220541D01*
X432274Y223315D01*
Y251774D01*
X433500Y253000D01*
X463500D01*
X464500Y252000D01*
Y231000D01*
X468500Y227000D01*
X478816D01*
X486816Y219000D01*
X496500D01*
X507500Y208000D01*
Y204894D01*
X511394Y201000D01*
X515500D01*
G01X420900Y251000D02*
Y246800D01*
G01X415000Y251000D02*
Y246800D01*
G01X461500Y268409D02*
X455988D01*
X448189Y260610D01*
X429787D01*
X424000Y254823D01*
Y246739D01*
X421826Y244565D01*
X419434D01*
X417199Y246800D01*
X415000D01*
G01X425000Y381000D02*
X426000Y380000D01*
Y342501D01*
X427500Y341001D01*
Y324500D01*
X438500Y313500D01*
Y309500D01*
X449000Y299000D01*
X454565D01*
X456600Y296965D01*
Y294500D01*
G01X430000Y381000D02*
Y379500D01*
X428000Y377500D01*
Y353000D01*
X432000Y349000D01*
Y345390D01*
X429000Y342390D01*
Y326000D01*
X441500Y313500D01*
Y309000D01*
X447500Y303000D01*
X454000D01*
X456500Y305500D01*
G01X430000Y386500D02*
X427300Y389200D01*
Y390800D01*
X424000Y394100D01*
G01X426600Y406500D02*
X431000D01*
G01X426600Y411500D02*
X431000D01*
G01X438374Y209933D02*
X436510Y211797D01*
Y224761D01*
X436749Y225000D01*
G01D02*
X439735Y227986D01*
Y238841D01*
X439500Y239076D01*
Y241900D01*
G01X435000D02*
Y239000D01*
X436500Y237500D01*
G01X444000Y241900D02*
X439500D01*
G01X435000Y250500D02*
Y246100D01*
G01X436600Y297500D02*
X441500D01*
G01X433382Y360466D02*
X435500Y358348D01*
Y352000D01*
X434250Y350750D01*
Y344960D01*
X431000Y341710D01*
Y327000D01*
X444500Y313500D01*
Y309000D01*
X447000Y306500D01*
X451000D01*
G01X442500Y336089D02*
X443710Y337299D01*
Y376263D01*
X447730Y380283D01*
Y407770D01*
X444000Y411500D01*
G01X440000Y332500D02*
X442500D01*
X461500Y313500D01*
Y311000D01*
G01X434000Y328000D02*
X436000Y330000D01*
Y333276D01*
X435530Y333746D01*
X435010D01*
X434540Y334216D01*
Y335746D01*
X435010Y336216D01*
X435530D01*
X436000Y336686D01*
Y338216D01*
X435530Y338686D01*
X435010D01*
X434540Y339156D01*
Y340686D01*
X435010Y341156D01*
X435530D01*
X436000Y341626D01*
Y343500D01*
X437230Y344730D01*
Y346852D01*
X437700Y347322D01*
X439480D01*
X439950Y347792D01*
Y349322D01*
X439480Y349792D01*
X437700D01*
X437230Y350262D01*
Y351792D01*
X437700Y352262D01*
X439480D01*
X439950Y352732D01*
Y354262D01*
X439480Y354732D01*
X437700D01*
X437230Y355202D01*
Y356732D01*
X437700Y357202D01*
X439480D01*
X439950Y357672D01*
Y359202D01*
X439480Y359672D01*
X437700D01*
X437230Y360142D01*
Y361194D01*
X433500Y364924D01*
Y366500D01*
G01X444000Y406500D02*
X446000Y404500D01*
Y381000D01*
X441770Y376770D01*
Y365876D01*
X441735Y365841D01*
Y343735D01*
X439500Y341500D01*
G01X439600Y386500D02*
X441000Y385100D01*
Y380000D01*
X430000Y369000D01*
Y357500D01*
X433000Y354500D01*
Y353500D01*
G01X435400Y386500D02*
X430000D01*
G01X444000Y406500D02*
X439600D01*
G01X435400D02*
X431000D01*
G01X444000Y411500D02*
X439600D01*
G01X435400D02*
X431000D01*
G01X460029Y188280D02*
Y188278D01*
X461996Y186311D01*
G01X456090Y184343D02*
X458059Y182374D01*
G01X454122Y217807D02*
Y224302D01*
X453600Y224824D01*
Y229178D01*
X454122Y229700D01*
Y238522D01*
X457500Y241900D01*
G01X475500Y82500D02*
X479770Y86770D01*
X481218D01*
X500474Y106026D01*
Y114692D01*
X508500Y122718D01*
Y174500D01*
X511500Y177500D01*
Y177552D01*
X511730Y177782D01*
Y193717D01*
X500500Y204947D01*
Y207000D01*
X495500Y212000D01*
X491000D01*
X481000Y222000D01*
X471000D01*
X468000Y225000D01*
X464661D01*
X462926Y226735D01*
X458765D01*
X458000Y227500D01*
X457500D01*
G01X470500Y82500D02*
X476500Y88500D01*
X480501D01*
X490098Y98097D01*
Y98761D01*
X488462Y100397D01*
Y101061D01*
X489545Y102144D01*
X490209D01*
X491845Y100508D01*
X492509D01*
X493592Y101591D01*
Y102255D01*
X491956Y103891D01*
Y104555D01*
X493039Y105638D01*
X493703D01*
X495339Y104002D01*
X496003D01*
X498000Y105999D01*
Y114767D01*
X506733Y123500D01*
Y147657D01*
X506735Y147659D01*
Y175234D01*
X510000Y178499D01*
Y193000D01*
X498500Y204500D01*
Y206501D01*
X495501Y209500D01*
X490000D01*
X479500Y220000D01*
X470500D01*
X469500Y221000D01*
X460000D01*
X457500Y223500D01*
G01X448500Y241900D02*
X453000D01*
G01X448500D02*
Y237500D01*
G01X462000Y241900D02*
X457500D01*
G01X452400Y284500D02*
Y289500D01*
G01Y284500D02*
Y279500D01*
G01X447000Y283000D02*
X448500Y284500D01*
X452400D01*
G01X460800Y294200D02*
X456900D01*
X456600Y294500D01*
G01X452400D02*
Y289500D01*
G01X473600Y91500D02*
Y96500D01*
G01X479500Y92500D02*
X478500Y91500D01*
X473600D01*
G01X479246Y178464D02*
X485864D01*
X488400Y181000D01*
G01X467901Y168595D02*
Y168596D01*
X465933Y170564D01*
G01X463900Y175500D02*
Y176404D01*
X465933Y178437D01*
G01X467902Y188281D02*
Y188280D01*
X465933Y186311D01*
G01X467902Y188281D02*
X475281D01*
X475946Y188946D01*
X477446D01*
X481500Y193000D01*
G01X471839Y211902D02*
X471838D01*
X469870Y213870D01*
G01X467902Y207965D02*
X469870Y209933D01*
G01X473600Y355100D02*
X467400D01*
X467000Y355500D01*
G01X488400Y163000D02*
Y167500D01*
G01X501500Y192500D02*
Y184000D01*
X499765Y182265D01*
X493865D01*
X492600Y181000D01*
G01X484000Y166000D02*
X485500Y167500D01*
X488400D01*
G01X485033Y174934D02*
X486834D01*
X488400Y176500D01*
G01X492600Y185500D02*
X498060D01*
G01X488400Y197500D02*
X484612D01*
X483871Y198241D01*
G01X484000Y185500D02*
X488400D01*
G01X497500Y214000D02*
X502230Y209270D01*
Y205664D01*
X513460Y194434D01*
Y177013D01*
X511500Y175053D01*
Y175000D01*
X510230Y173730D01*
Y122001D01*
X503005Y114776D01*
Y99494D01*
G01X507000Y192500D02*
X497000Y202500D01*
X492600D01*
G01X496100Y268600D02*
X498000D01*
X500500Y271100D01*
G01X488500Y354600D02*
Y359000D01*
G01X493500Y354600D02*
Y359000D01*
G01X481000Y341000D02*
X486661D01*
X493500Y347839D01*
Y350400D01*
G01X497000Y341000D02*
X500500D01*
X503100Y343600D01*
Y345500D01*
G01X488500Y350400D02*
Y346000D01*
G01X554600Y259500D02*
Y255430D01*
X532670Y233500D01*
X528000D01*
X525000Y230500D01*
Y111500D01*
X519000Y105500D01*
X508000D01*
G01Y110500D02*
X508525Y111025D01*
X509189D01*
X511275Y108939D01*
X511939D01*
X513022Y110022D01*
Y110686D01*
X510936Y112772D01*
Y113436D01*
X512019Y114519D01*
X512683D01*
X514769Y112433D01*
X515433D01*
X516516Y113516D01*
Y114180D01*
X514430Y116266D01*
Y116930D01*
X515550Y118050D01*
Y122388D01*
X516020Y122858D01*
X520730D01*
X521200Y123328D01*
Y124858D01*
X520730Y125328D01*
X516020D01*
X515550Y125798D01*
Y127328D01*
X516020Y127798D01*
X520730D01*
X521200Y128268D01*
Y129798D01*
X520730Y130268D01*
X516020D01*
X515550Y130738D01*
Y132268D01*
X516020Y132738D01*
X520730D01*
X521200Y133208D01*
Y134738D01*
X520730Y135208D01*
X516020D01*
X515550Y135678D01*
Y136821D01*
X521029Y142300D01*
Y232146D01*
X526354Y237471D01*
X531024D01*
X539910Y246357D01*
Y262538D01*
X535000Y267448D01*
Y282500D01*
X539500Y287000D01*
X545400D01*
G01X554600Y306500D02*
Y309690D01*
X552960Y311330D01*
X540930D01*
X533800Y304200D01*
Y283800D01*
X530000Y280000D01*
Y269501D01*
X538180Y261321D01*
Y247074D01*
X530307Y239201D01*
X525637D01*
X519299Y232863D01*
Y143300D01*
X513350Y137351D01*
Y120850D01*
X508000Y115500D01*
G01X498500Y354600D02*
X503000D01*
G01X498500Y350400D02*
X501100D01*
X503100Y348400D01*
Y345500D01*
G01X522500Y114500D02*
X523000Y115000D01*
Y231670D01*
X527071Y235741D01*
X531741D01*
X541640Y245640D01*
Y263255D01*
X541500Y263395D01*
Y263447D01*
X536730Y268217D01*
Y281570D01*
X539160Y284000D01*
X553850D01*
X554600Y283250D01*
Y281500D01*
G01X532300Y415901D02*
Y408800D01*
X530000Y406500D01*
G01X527300Y415901D02*
X532300D01*
G01Y420101D02*
Y425700D01*
G01X555500Y65000D02*
X551500D01*
X550000Y63500D01*
X549000D01*
G01D02*
X548500Y64000D01*
X544600D01*
G01X555700Y70500D02*
X550600D01*
X549500Y69400D01*
G01X544600Y69000D02*
X545000Y69400D01*
X549500D01*
G01X541000Y96000D02*
Y76800D01*
X534600Y70400D01*
Y65400D01*
X536000Y64000D01*
X540400D01*
G01X551000Y232400D02*
X546500D01*
G01X543100Y227500D02*
X543600Y228000D01*
X548125D01*
X548158Y228033D01*
G01X545250Y263750D02*
Y256300D01*
G01X550400Y264000D02*
Y259500D01*
G01Y264000D02*
X545500D01*
X545250Y263750D01*
G01X545200Y277100D02*
X541953D01*
X539977Y275124D01*
G01X550400Y277000D02*
X547764D01*
X547664Y277100D01*
X545200D01*
G01X550400Y281500D02*
Y277000D01*
G01X550200Y272100D02*
X541982D01*
X540318Y270436D01*
G01X537500Y296607D02*
X537607D01*
X542900Y301900D01*
X545200D01*
G01X550400Y302000D02*
X547764D01*
X547664Y301900D01*
X545200D01*
G01X550400Y306500D02*
Y302000D01*
G01X550200Y292250D02*
X545200D01*
G01X549600Y287000D02*
Y288600D01*
X550200Y289200D01*
Y292250D01*
G01X539500Y292000D02*
X539750Y292250D01*
X545200D01*
G01X548500Y411000D02*
X549000Y411500D01*
X552900D01*
G01X538558Y413779D02*
X539937Y412400D01*
X543500D01*
G01X550369Y427558D02*
X551827Y426100D01*
X555500D01*
G01X538558Y427558D02*
X540016Y426100D01*
X543500D01*
G01X555500Y232400D02*
Y230357D01*
X553122Y227979D01*
G01X555500Y232400D02*
X551000D01*
G01X590650Y245680D02*
X587460Y242490D01*
X566351D01*
X566326Y242465D01*
X564474D01*
X564449Y242490D01*
X551470D01*
X551000Y242020D01*
Y236600D01*
G01X581400Y262100D02*
Y259900D01*
X578500Y257000D01*
X569600D01*
X567550Y259050D01*
Y263750D01*
G01D02*
X557486D01*
X557236Y264000D01*
X554600D01*
G01X581400Y272100D02*
Y276100D01*
X579500Y278000D01*
X569500D01*
X567550Y276050D01*
Y272450D01*
G01X554600Y277000D02*
X557236D01*
X557336Y277100D01*
X558400D01*
X563050Y272450D01*
X567550D01*
G01X567050Y300950D02*
Y305050D01*
X568100Y306100D01*
X577500D01*
X581500Y302100D01*
G01X554600Y302000D02*
X557236D01*
X557336Y301900D01*
X560200D01*
X561150Y300950D01*
X567050D01*
G01Y292250D02*
X554400D01*
G01X567050D02*
Y288850D01*
X571900Y284000D01*
X579500D01*
X581400Y282100D01*
G01X557100Y407000D02*
X561261D01*
X561731Y407470D01*
Y408500D01*
G01X562180Y413779D02*
X563359Y412600D01*
X567500D01*
G01X561731Y408500D02*
Y409269D01*
X559500Y411500D01*
X557100D01*
G01X562180Y427558D02*
X563638Y426100D01*
X567000D01*
G01X582500Y75400D02*
X577500D01*
G01X577200Y70000D02*
Y75100D01*
X577500Y75400D01*
G01X577200Y70000D02*
X573500D01*
X572870Y69370D01*
Y67570D01*
G01X576500Y98000D02*
X577500Y97000D01*
Y79600D01*
G01X571800Y396500D02*
X572000Y396300D01*
Y390700D01*
G01X581100Y407500D02*
X584500D01*
X585500Y408500D01*
Y409500D01*
G01X572500Y413500D02*
X574000Y412000D01*
X576900D01*
G01X581100D02*
X584000D01*
X585500Y410500D01*
Y409500D01*
G01X573991Y427558D02*
X575449Y426100D01*
X579000D01*
G01X598000Y141900D02*
X592900D01*
X592000Y141000D01*
G01X598000Y146100D02*
X592100D01*
X592000Y146000D01*
G01X598000Y163400D02*
X592400D01*
X592000Y163000D01*
G01X598000Y153900D02*
X594400D01*
X592000Y151500D01*
G01Y157063D02*
X593037Y158100D01*
X598000D01*
G01Y173900D02*
X592900D01*
X592000Y173000D01*
G01Y178000D02*
X592100Y178100D01*
X598000D01*
G01X592000Y168000D02*
X592400Y167600D01*
X598000D01*
G01X597000Y199900D02*
X596902Y199802D01*
Y195065D01*
G01X587500Y190000D02*
Y194595D01*
X587970Y195065D01*
X591902D01*
G01X602500Y183000D02*
Y184000D01*
X601902Y184598D01*
Y190865D01*
G01X599400Y261500D02*
X596777D01*
X596307Y261030D01*
Y258950D01*
X595837Y258480D01*
X594307D01*
X593837Y258950D01*
Y261030D01*
X593367Y261500D01*
X591000D01*
G01Y278500D02*
X591500Y279000D01*
X599400D01*
G01X590748Y418725D02*
X591000Y418473D01*
Y413100D01*
G01X597613Y413779D02*
X598292Y413100D01*
X602500D01*
G01X597613Y427558D02*
X599071Y426100D01*
X602700D01*
G01X617000Y143400D02*
X620100D01*
X622000Y141500D01*
G01X617000Y163400D02*
X620600D01*
X622000Y162000D01*
G01X617000Y153400D02*
X620200D01*
X622000Y151600D01*
G01X617000Y147600D02*
X620900D01*
X622000Y146500D01*
G01Y157000D02*
X621400Y157600D01*
X617000D01*
G01X615500Y181100D02*
X621600D01*
X622000Y181500D01*
G01Y175500D02*
X620600Y176900D01*
X615500D01*
G01X617000Y167600D02*
X621498D01*
X622035Y167063D01*
G01X606902Y190865D02*
Y186000D01*
G01X604000Y254500D02*
Y255000D01*
X603600Y255400D01*
Y261500D01*
G01Y279000D02*
X609500Y273100D01*
Y254500D01*
G01X609424Y413779D02*
X609603Y413600D01*
X614500D01*
G01X609424Y427558D02*
X610882Y426100D01*
X614000D01*
G01X637900Y108000D02*
X633500D01*
G01X637900Y102000D02*
X633500D01*
G01X637900Y96500D02*
X633500D01*
G01X630000Y196774D02*
X625500D01*
G01D02*
Y192500D01*
X628500Y189500D01*
G01X625500Y200974D02*
Y203139D01*
X623264Y205375D01*
X623000D01*
G01D02*
X621000Y203375D01*
Y200974D01*
G54D19*
X33500Y282900D03*
X29000D03*
X33500Y287100D03*
X29000D03*
X57700Y65500D03*
Y69700D03*
X53000D03*
Y65500D03*
X53500Y88400D03*
Y92600D03*
X53000Y144400D03*
Y148600D03*
Y204900D03*
Y209100D03*
Y258400D03*
Y262600D03*
X79900Y71100D03*
Y75300D03*
X72100Y81700D03*
Y85900D03*
X74300Y95300D03*
Y91100D03*
X78800Y95300D03*
Y91100D03*
X69800D03*
Y95300D03*
X76000Y240200D03*
Y244400D03*
X80500Y240200D03*
Y244400D03*
X71500D03*
Y240200D03*
X66000Y301400D03*
Y305600D03*
X70000Y338400D03*
Y342600D03*
X86000Y83300D03*
Y79100D03*
X87800Y91100D03*
Y95300D03*
X83300Y91100D03*
Y95300D03*
X89600Y244400D03*
Y240200D03*
X85000Y244400D03*
Y240200D03*
X90800Y278900D03*
Y283100D03*
X85800D03*
Y278900D03*
X95000Y356400D03*
X88200Y355300D03*
X95000Y360600D03*
X88200Y359500D03*
X103500Y309400D03*
Y313600D03*
X113000Y356400D03*
X99500D03*
X104000D03*
X108500D03*
X113000Y360600D03*
X105500Y368900D03*
Y373100D03*
X99500Y360600D03*
X104000D03*
X108500D03*
X128000Y309400D03*
Y313600D03*
X126500Y356400D03*
X117500D03*
X122000D03*
X126500Y360600D03*
X117500D03*
X122000D03*
X137500Y355900D03*
Y360100D03*
X163000Y350400D03*
Y354600D03*
X180000Y406600D03*
Y402400D03*
X186460Y60220D03*
Y64420D03*
X188500Y298100D03*
Y293900D03*
X215500Y65600D03*
Y61400D03*
X220000Y65600D03*
Y61400D03*
X217300Y293100D03*
Y297300D03*
X212800Y293100D03*
Y297300D03*
X208300Y293100D03*
Y297300D03*
X210500Y340900D03*
Y345100D03*
X234310Y58390D03*
Y62590D03*
X239311Y58400D03*
X246122D03*
X251122D03*
X239311Y62600D03*
X246122D03*
X251122D03*
X254000Y230600D03*
Y226400D03*
Y217400D03*
Y221600D03*
X265807Y58400D03*
X270807D03*
X265807Y62600D03*
X270807D03*
X259000Y226400D03*
Y230600D03*
X280055Y58400D03*
X285055D03*
X280055Y62600D03*
X285055D03*
X279500Y188000D03*
Y183800D03*
X279000Y216400D03*
Y229600D03*
Y233800D03*
Y220600D03*
X290000Y284400D03*
X285500D03*
X290000Y288600D03*
X285500D03*
X297303Y58400D03*
X302303D03*
X297303Y62600D03*
X302303D03*
X291000Y229900D03*
Y234100D03*
X324500Y285900D03*
Y290100D03*
X318500Y387900D03*
Y392100D03*
X333500Y251100D03*
Y255300D03*
X335000Y286400D03*
X339500D03*
X335000Y290600D03*
X339500D03*
X352000Y133400D03*
Y137600D03*
X350500Y178900D03*
Y183100D03*
X347000Y233400D03*
Y237600D03*
X344000Y286400D03*
X348500D03*
X344000Y290600D03*
X348500D03*
X377000Y76900D03*
Y81100D03*
X391900Y251000D03*
X386000D03*
X380100D03*
X391900Y255200D03*
X386000D03*
X380100D03*
X403700Y251000D03*
X397800D03*
X409300D03*
X403700Y255200D03*
X397800D03*
X409300D03*
X398000Y347100D03*
Y342900D03*
X427500Y91900D03*
Y96100D03*
X420900Y251000D03*
X415000D03*
X420900Y255200D03*
X415000D03*
X417000Y347100D03*
Y342900D03*
X424000Y398300D03*
Y394100D03*
X432000Y91900D03*
Y96100D03*
X441500Y107900D03*
Y112100D03*
X437000Y107900D03*
Y112100D03*
X430500Y164900D03*
Y159100D03*
Y154900D03*
Y169100D03*
X430600Y179500D03*
Y183700D03*
X430000Y198700D03*
Y202900D03*
X435000Y246100D03*
Y241900D03*
X444000Y246100D03*
Y241900D03*
X439500D03*
Y246100D03*
X453000Y113900D03*
Y118100D03*
X458500Y113900D03*
Y118100D03*
X462000Y241900D03*
Y246100D03*
X457500D03*
Y241900D03*
X448500Y246100D03*
Y241900D03*
X453000D03*
Y246100D03*
X478000Y182111D03*
Y186311D03*
X496100Y268600D03*
Y272800D03*
X488500Y354600D03*
Y350400D03*
X498500Y354600D03*
Y350400D03*
X493500Y354600D03*
Y350400D03*
X508500Y385400D03*
Y389600D03*
X503500Y385400D03*
Y389600D03*
X527800Y265300D03*
Y261100D03*
X527300Y420101D03*
Y415901D03*
X532300D03*
Y420101D03*
X539000Y160400D03*
Y164600D03*
X551000Y202400D03*
Y206600D03*
Y212900D03*
Y217100D03*
Y232400D03*
X546500D03*
X551000Y236600D03*
X546500D03*
X545250Y267950D03*
Y263750D03*
X545200Y277100D03*
Y281300D03*
Y292250D03*
Y296450D03*
Y301900D03*
Y306100D03*
X543500Y416600D03*
Y412400D03*
Y421900D03*
Y426100D03*
X555700Y70500D03*
Y74700D03*
X555500Y65000D03*
Y60800D03*
X560000Y232400D03*
X555500D03*
X560000Y236600D03*
X555500D03*
X567500Y408400D03*
X567000Y421900D03*
Y426100D03*
X555500Y421900D03*
Y426100D03*
X567500Y412600D03*
X582500Y75400D03*
X577500D03*
X577200Y65800D03*
Y70000D03*
X582500Y79600D03*
X577500D03*
X575400Y232400D03*
Y236600D03*
X579000Y421900D03*
Y426100D03*
X598000Y141900D03*
Y146100D03*
Y153900D03*
Y158100D03*
Y163400D03*
Y167600D03*
Y173900D03*
Y178100D03*
X591902Y195065D03*
Y190865D03*
X596902D03*
Y195065D03*
X601902Y190865D03*
Y195065D03*
X602500Y408900D03*
X591000D03*
X602700Y421900D03*
Y426100D03*
X602500Y413100D03*
X591000D03*
X617000Y147600D03*
Y143400D03*
Y157600D03*
Y153400D03*
Y163400D03*
Y167600D03*
X615500Y176900D03*
Y181100D03*
X606902Y190865D03*
Y195065D03*
X621000Y196774D03*
Y200974D03*
X614000Y421900D03*
Y426100D03*
X614500Y409400D03*
Y413600D03*
X625500Y196774D03*
X630000D03*
X625500Y200974D03*
X630000D03*
G54D28*
X174850Y338800D03*
Y353800D03*
Y348800D03*
Y343800D03*
X196950Y338800D03*
Y343800D03*
Y348800D03*
Y353800D03*
G54D46*
X640952Y201181D03*
Y220867D03*
G54D37*
X531600Y351999D03*
Y369401D03*
G54D56*
G01X251122Y58400D02*
G03X249372Y54175I4225J-4225D01*
G01Y50146D01*
X249371Y50147D01*
Y25217D01*
G03X249853Y24053I1646J0D01*
G01X250153Y23753D01*
X250154Y23751D01*
G02X250590Y22700I-1051J-1052D01*
G01Y13781D01*
G01X246122Y58400D02*
G02X247872Y54175I-4225J-4225D01*
G01Y50146D01*
X247871Y50145D01*
Y25176D01*
G02X247418Y24082I-1547J0D01*
G01X247018Y23682D01*
G03X246653Y22801I881J-881D01*
G01Y13781D01*
G01X251122Y62600D02*
G02X249372Y66825I4225J4225D01*
G01Y74248D01*
G02X250222Y76300I2902J0D01*
G01X247022D02*
G02X247872Y74248I-2052J-2052D01*
G01Y65870D01*
G02X246797Y63275I-3670J0D01*
G01X246122Y62600D01*
G01X270807Y58400D02*
X270616Y58209D01*
G03X269057Y54445I3764J-3764D01*
G01Y25156D01*
G03X269260Y24401I1499J-2D01*
G03X269496Y24096I1294J757D01*
G01X269796Y23796D01*
G02X270275Y22640I-1156J-1156D01*
G01Y13781D01*
G01X265807Y58400D02*
G02X267557Y54175I-4225J-4225D01*
G01Y25024D01*
G02X267378Y24400I-1181J1D01*
G02X267211Y24189I-1003J622D01*
G01X266661Y23639D01*
G03X266338Y22859I780J-780D01*
G01Y13781D01*
G01X264339Y35300D02*
G03X262287Y36150I-2052J-2052D01*
G01X261100D01*
G02X257900Y39350I0J3200D01*
G01Y46119D01*
G03X256939Y48439I-3281J0D01*
G01X255739Y49639D01*
G02X254600Y52390I2751J2750D01*
G01Y69629D01*
G02X257139Y75761I8670J2D01*
G01X264839Y83461D01*
G02X270971Y86000I6130J-6131D01*
G01X278500D01*
G03X281231Y87131I0J3863D01*
G01X292750Y98650D01*
G03X294200Y102151I-3501J3501D01*
G01Y127399D01*
G02X296194Y132216I6811J2D01*
G01X329089Y165111D01*
X329182Y165203D01*
G02X332799Y166700I3618J-3624D01*
G01X372248D01*
G03X374689Y167711I0J3452D01*
G01X374840Y167862D01*
G02X378252Y169275I3412J-3412D01*
G01X384384D01*
G01X264339Y38500D02*
G02X262287Y37650I-2052J2052D01*
G01X261100D01*
G02X259400Y39350I0J1700D01*
G01Y46120D01*
G03X258000Y49500I-4781J0D01*
G01X256800Y50700D01*
G02X256100Y52390I1690J1690D01*
G01Y58579D01*
G02X256560Y59039I460J0D01*
G03X257020Y59499I0J460D01*
G01Y60859D01*
G03X256560Y61319I-460J0D01*
G02X256100Y61779I0J460D01*
G01Y69630D01*
G02X258200Y74700I7170J0D01*
G01X265900Y82400D01*
G02X270970Y84500I5070J-5070D01*
G01X278501D01*
G03X282292Y86070I-1J5363D01*
G01X293811Y97589D01*
G03X295700Y102152I-4562J4561D01*
G01Y127400D01*
G02X297255Y131155I5311J0D01*
G01X330150Y164050D01*
X330240Y164139D01*
G02X332800Y165200I2561J-2560D01*
G01X372247D01*
G03X375750Y166650I2J4952D01*
G01X375901Y166801D01*
G02X378251Y167775I2351J-2351D01*
G01X384384D01*
G01X270807Y62600D02*
G02X269057Y66825I4225J4225D01*
G01Y74248D01*
G02X269907Y76300I2902J0D01*
G01X265807Y62600D02*
G03X267557Y66825I-4225J4225D01*
G01Y74248D01*
G03X266707Y76300I-2902J0D01*
G01X285055Y58400D02*
G03X283305Y54175I4225J-4225D01*
G01Y48454D01*
G03X283700Y47500I1349J0D01*
G01X283747Y47453D01*
G02X284804Y44899I-2553J-2552D01*
G01Y24980D01*
G03X284979Y24391I1075J-1D01*
G03X285119Y24220I898J592D01*
G01X285619Y23720D01*
G02X286023Y22745I-975J-975D01*
G01Y13781D01*
G01X280055Y58400D02*
G02X281805Y54175I-4225J-4225D01*
G01Y48455D01*
G03X282639Y46439I2849J-2D01*
G01X282686Y46392D01*
G02X283304Y44900I-1492J-1492D01*
G01Y24988D01*
G02X283137Y24407I-1093J0D01*
G02X282984Y24215I-926J581D01*
G01X282384Y23615D01*
G03X282086Y22896I719J-719D01*
G01Y13781D01*
G01X280087Y35300D02*
X279709Y35679D01*
G03X278300Y36262I-1408J-1409D01*
G01X277800D01*
G02X275100Y38962I0J2700D01*
G01Y76900D01*
G02X279300Y81100I4200J0D01*
G01X280300D01*
G03X281836Y81736I0J2173D01*
G01X297708Y97608D01*
G03X299900Y102900I-5292J5292D01*
G01Y125099D01*
G02X302460Y131284I8744J3D01*
G01X303088Y131911D01*
X303089D01*
X331839Y160661D01*
G02X336281Y162500I4440J-4441D01*
G01X375901D01*
G03X377556Y163187I-1J2339D01*
G01X378612Y164242D01*
G02X381394Y165395I2783J-2782D01*
G01X383720D01*
G01X280087Y38500D02*
G02X278305Y37762I-1782J1782D01*
G01X277800D01*
G02X276600Y38962I0J1200D01*
G01Y43647D01*
G02X276935Y43982I335J0D01*
G03X277270Y44317I0J335D01*
G01Y45927D01*
G03X276935Y46262I-335J0D01*
G02X276600Y46597I0J335D01*
G01Y66678D01*
G02X276915Y66993I315J0D01*
G03X277230Y67308I0J315D01*
G01Y68958D01*
G03X276915Y69273I-315J0D01*
G02X276600Y69588I0J315D01*
G01Y76900D01*
G02X279300Y79600I2700J0D01*
G01X280301D01*
G03X282897Y80675I0J3673D01*
G01X298769Y96547D01*
G03X301400Y102901I-6353J6352D01*
G01Y125100D01*
G02X303521Y130222I7243J1D01*
G01X332900Y159600D01*
G02X336280Y161000I3380J-3380D01*
G01X375902D01*
G03X378618Y162126I-1J3840D01*
G01X379673Y163181D01*
G02X381395Y163895I1723J-1721D01*
G01X383720D01*
G01X295835Y35300D02*
G03X293783Y36150I-2052J-2052D01*
G01X291700D01*
G02X288200Y39650I0J3500D01*
G01Y72070D01*
G02X289439Y75061I4231J-1D01*
G03X289900Y76174I-1113J1113D01*
G01Y80601D01*
G02X291950Y85550I7000J-1D01*
G01X305866Y99466D01*
G03X308200Y105100I-5633J5634D01*
G01Y121884D01*
G02X311250Y129250I10415J2D01*
G01X338400Y156400D01*
G02X343231Y158400I4829J-4830D01*
G01X379000D01*
G03X380499Y159021I0J2120D01*
G01X382211Y160733D01*
G02X384003Y161475I1792J-1793D01*
G01X384816D01*
G01X285055Y62600D02*
G02X283305Y66825I4225J4225D01*
G01Y70392D01*
G02X283511Y70889I703J0D01*
G03X284205Y72567I-1677J1676D01*
G01Y74248D01*
G02X285055Y76300I2902J0D01*
G01X280055Y62600D02*
G03X281805Y66825I-4225J4225D01*
G01Y70393D01*
G02X282450Y71950I2203J-1D01*
G03X282705Y72566I-616J616D01*
G01Y74248D01*
G03X281855Y76300I-2902J0D01*
G01X302303Y58400D02*
G03X300553Y54175I4225J-4225D01*
G01Y53932D01*
G03X301022Y52800I1601J0D01*
G01X301761Y52061D01*
G02X302800Y49550I-2510J-2509D01*
G01Y32858D01*
G02X301700Y30200I-3757J-2D01*
G01X301350Y29850D01*
G03X300552Y27923I1927J-1927D01*
G01Y24947D01*
G03X300685Y24449I994J-1D01*
G03X300843Y24244I860J499D01*
G01X301393Y23694D01*
G02X301771Y22781I-913J-913D01*
G01Y13781D01*
G01X297303Y58400D02*
G02X299053Y54175I-4225J-4225D01*
G01Y53932D01*
G03X299961Y51739I3101J-1D01*
G01X300700Y51000D01*
G02X301300Y49551I-1449J-1449D01*
G01Y32857D01*
G02X300639Y31261I-2257J0D01*
G01X300289Y30911D01*
G03X299052Y27922I2988J-2987D01*
G01Y25021D01*
G02X298886Y24420I-1174J1D01*
G02X298708Y24191I-1009J600D01*
G01X298158Y23641D01*
G03X297834Y22859I782J-782D01*
G01Y13781D01*
G01X295835Y38500D02*
G02X293783Y37650I-2052J2052D01*
G01X291700D01*
G02X289700Y39650I0J2000D01*
G01Y41895D01*
G02X290150Y42345I450J0D01*
G03X290600Y42795I0J450D01*
G01Y44175D01*
G03X290150Y44625I-450J0D01*
G02X289700Y45075I0J450D01*
G01Y72069D01*
G02X290500Y74000I2731J0D01*
G03X291400Y76175I-2174J2173D01*
G01Y80600D01*
G02X293011Y84489I5500J0D01*
G01X306927Y98405D01*
G03X309700Y105099I-6694J6694D01*
G01Y121885D01*
G02X312311Y128189I8915J0D01*
G01X339461Y155339D01*
G02X343230Y156900I3769J-3769D01*
G01X379001D01*
G03X381560Y157960I-1J3620D01*
G01X383272Y159672D01*
G02X384002Y159975I731J-731D01*
G01X384816D01*
G01X295835Y44900D02*
X295334Y45400D01*
G03X294370Y45800I-965J-964D01*
G02X292300Y47870I0J2070D01*
G01Y70701D01*
G02X292541Y72008I3673J-2D01*
G02X293192Y73014I2676J-1018D01*
G01X293837Y73659D01*
G03X294600Y75500I-1839J1841D01*
G01Y79001D01*
G02X296665Y83987I7053J-1D01*
G01X312239Y99561D01*
G03X314600Y105261I-5700J5700D01*
G01Y121309D01*
G02X316589Y126111I6792J0D01*
G01X339354Y148876D01*
G02X343999Y150800I4645J-4646D01*
G01X375191D01*
G03X379537Y152601I-1J6146D01*
G01X382969Y156033D01*
G01X295835Y48100D02*
X295505Y47770D01*
G02X294370Y47300I-1135J1135D01*
G02X293800Y47870I0J570D01*
G01Y70700D01*
G02X293943Y71474I2173J-1D01*
G02X294253Y71953I1274J-485D01*
G01X294898Y72598D01*
G03X296100Y75501I-2900J2901D01*
G01Y79000D01*
G02X297726Y82926I5553J0D01*
G01X298957Y84157D01*
G02X299365I204J-205D01*
G01X299367Y84155D01*
G03X299775I204J205D01*
G01X300980Y85360D01*
G03Y85768I-205J204D01*
G01X300978Y85770D01*
G02Y86178I205J204D01*
G01X313300Y98500D01*
G03X316100Y105262I-6761J6760D01*
G01Y121308D01*
G02X317650Y125050I5292J0D01*
G01X340415Y147815D01*
G02X344000Y149300I3585J-3585D01*
G01X375191D01*
G03X380598Y151540I0J7646D01*
G01X384030Y154972D01*
G01X314763Y85237D02*
G03X312707Y84386I-1J-2907D01*
G01X312661Y84339D01*
X301711Y73389D01*
G03X300553Y70593I2796J-2796D01*
G01Y66825D01*
G03X302303Y62600I5975J0D01*
G01X312500Y87500D02*
G02X311651Y85452I-2897J1D01*
G01X311500Y85300D01*
X300650Y74450D01*
G03X299053Y70592I3857J-3856D01*
G01Y66825D01*
G02X297303Y62600I-5975J0D01*
G01X345301Y189899D02*
X344484D01*
G02X343536Y190291I-1J1340D01*
G03X342334Y190790I-1203J-1200D01*
G01X341037D01*
G03X340187Y190438I0J-1202D01*
G01X335497Y185748D01*
G02X333450Y184900I-2047J2046D01*
G01X326980D01*
G02X325036Y185705I0J2749D01*
G01X324137Y186604D01*
G02X323530Y188069I1464J1465D01*
G01Y188956D01*
G03X323160Y189849I-1263J0D01*
G01X322710Y190299D01*
G01X345301Y193099D02*
X344484D01*
G03X343600Y192767I-1J-1340D01*
G02X342333Y192290I-1267J1445D01*
G01X341036D01*
G03X339126Y191499I0J-2702D01*
G01X334436Y186809D01*
G02X333451Y186400I-986J984D01*
G01X326980D01*
G02X326097Y186766I0J1249D01*
G01X325198Y187665D01*
G02X325030Y188069I403J405D01*
G01Y188956D01*
G03X325028Y189079I-2763J17D01*
G02X325415Y189804I1390J-276D01*
G01X325910Y190299D01*
G01X365101Y191559D02*
X364827Y191285D01*
G02X362427Y191072I-1327J1328D01*
G03X360587Y191649I-1840J-2644D01*
G01X360523D01*
G02X357923Y192726I0J3677D01*
G01X357500Y193149D01*
G01X365101Y188359D02*
X364827Y188633D01*
G03X363400Y189224I-1427J-1427D01*
G02X361982Y189561I0J3152D01*
G02X361673Y189761I775J1537D01*
G03X360586Y190149I-1088J-1333D01*
G01X360523D01*
G02X360172Y190160I-13J5177D01*
G03X357974Y189122I349J-3585D01*
G01X357500Y188649D01*
G01X353300Y193149D02*
X352031Y191880D01*
G02X351210Y191541I-817J815D01*
G02X350690Y191647I-4J1308D01*
G03X348985Y192000I-1708J-3954D01*
G01X347243D01*
G02X345804Y192596I0J2034D01*
G01X345301Y193099D01*
G01X353300Y188649D02*
X352246Y189703D01*
G03X351651Y190076I-1111J-1111D01*
G02X351209Y190040I-436J2619D01*
G02X350095Y190270I-1J2808D01*
G03X348984Y190500I-1113J-2577D01*
G01X347243D01*
G02X346242Y190644I-2J3534D01*
G03X345743Y190341I374J-1178D01*
G01X345301Y189899D01*
G01X444280Y184343D02*
X444279D01*
X442311Y186311D01*
G01X448217Y184343D02*
X448216D01*
X446248Y186311D01*
G54D47*
G01X136000Y-65500D02*
Y-158000D01*
X506000D01*
Y-65500D01*
X136000D01*
G01X147700Y403600D02*
X148500Y402800D01*
X153900D01*
X156300Y405200D01*
X158500D01*
G01X151530Y406300D02*
X149900D01*
X147200Y409000D01*
G01X147700Y414200D02*
X147200Y413700D01*
Y409000D01*
G01X241441Y219300D02*
Y215000D01*
G01X246559Y228700D02*
Y235041D01*
X246100Y235500D01*
G01X316000Y-65500D02*
Y-158000D01*
G01X351600Y388700D02*
X349100Y391200D01*
X347000D01*
G01X352200Y398700D02*
X352100Y398800D01*
X347600D01*
G01X438374Y194185D02*
X436419Y192230D01*
X432494D01*
X431006Y193718D01*
G01X467902Y184343D02*
Y180407D01*
X467903Y180406D01*
G01X463966Y196154D02*
Y192217D01*
G01X477800Y355100D02*
Y383700D01*
X470500Y391000D01*
G01X566950Y220000D02*
X563140Y223810D01*
Y229140D01*
X564500Y230500D01*
Y233457D01*
G01X559500Y228000D02*
X560000Y228500D01*
Y232400D01*
G01X566700Y227500D02*
Y228700D01*
X569800Y231800D01*
X570000D01*
G01X553800Y240200D02*
X555500Y238500D01*
Y237800D01*
G01X564500Y235543D02*
Y238293D01*
X564350Y238443D01*
G01D02*
X562043D01*
X560200Y236600D01*
X560000D01*
G01X575400Y232400D02*
X574800Y231800D01*
X570000D01*
G54D29*
X180700Y413000D03*
X187300D03*
X306800Y194500D03*
X300200D03*
X373200Y106000D03*
X367800Y223000D03*
X361200D03*
X379800Y106000D03*
X413400Y285500D03*
X420000D03*
X413400Y293600D03*
X420000D03*
X493300Y126300D03*
X499900D03*
X508000Y245400D03*
X501400D03*
X546100Y320600D03*
X546500Y336400D03*
Y328800D03*
Y344100D03*
X568700Y199000D03*
X552700Y320600D03*
X553100Y336400D03*
Y328800D03*
Y344100D03*
X575300Y199000D03*
G54D38*
X564500Y233457D03*
Y235543D03*
G54D57*
G01X234842Y13781D02*
Y23605D01*
G02X235414Y24985I1951J0D01*
G01X235639Y25210D01*
G03X236211Y26590I-1379J1380D01*
G01Y55681D01*
G03X235639Y57061I-1951J0D01*
G01X234310Y58390D01*
G01X240508Y73100D02*
X240001Y72593D01*
G02X238908Y72140I-1093J1092D01*
G01X237960D01*
G03X236200Y70380I0J-1760D01*
G01Y66520D01*
X236203Y65302D01*
G02X235635Y63921I-1951J-5D01*
G01X234310Y62590D01*
G01X238779Y13781D02*
Y23622D01*
G03X238207Y25002I-1951J0D01*
G01X237983Y25226D01*
G02X237411Y26606I1379J1380D01*
G01Y55692D01*
G02X237983Y57072I1951J0D01*
G01X239311Y58400D01*
G01Y62600D02*
X237978Y63927D01*
G02X237404Y65303I1375J1381D01*
G01X237400Y66522D01*
Y70380D01*
G02X237960Y70940I560J0D01*
G01X238771D01*
G02X239961Y70447I0J-1683D01*
G01X240508Y69900D01*
G01X284500Y184300D02*
X283614Y185186D01*
G03X283338Y185300I-276J-277D01*
G01X281500D01*
G03X280646Y184946I0J-1207D01*
G01X279500Y183800D01*
G01X284500Y187500D02*
X283614Y186614D01*
G02X283338Y186500I-276J277D01*
G01X281500D01*
G02X280646Y186854I0J1207D01*
G01X279500Y188000D01*
G01X283850Y194500D02*
X282789Y195561D01*
G02X282400Y196500I939J939D01*
G01Y197538D01*
G02X282514Y197814I391J0D01*
G01X283400Y198700D01*
G01X279650Y194500D02*
X280882Y195732D01*
G03X281200Y196500I-768J768D01*
G01Y197538D01*
G03X281086Y197814I-391J0D01*
G01X280200Y198700D01*
G01X404909Y148910D02*
Y148912D01*
X402942Y150879D01*
G01X408847Y148910D02*
Y148911D01*
X406879Y150879D01*
G01X402942Y166627D02*
X404909Y168594D01*
Y168595D01*
G01X408847D02*
X406879Y166627D01*
G01X437650Y116599D02*
X438341Y115908D01*
G02X438600Y115283I-625J-625D01*
G01Y113862D01*
G02X438485Y113585I-391J0D01*
G01X437000Y112100D01*
G01X440850Y116599D02*
X439915Y115664D01*
G03X439800Y115387I276J-277D01*
G01Y113992D01*
G03X439936Y113664I464J0D01*
G01X441500Y112100D01*
G01X457330Y122167D02*
X456482Y121319D01*
G03X456350Y121000I319J-319D01*
G01Y120632D01*
G03X456620Y119980I922J0D01*
G01X458500Y118100D01*
G01X454130Y122167D02*
X455046Y121251D01*
G02X455150Y121000I-251J-251D01*
G01Y120632D01*
G02X454880Y119980I-922J0D01*
G01X453000Y118100D01*
G01X460027Y129224D02*
X461996Y131193D01*
G01X452155Y144973D02*
X452153D01*
X450185Y143005D01*
G01X448217Y144973D02*
X448216D01*
X446248Y143005D01*
G01X463965Y129224D02*
Y129225D01*
X465933Y131193D01*
G54D48*
G01X140100Y395600D02*
X141100Y394600D01*
X143500D01*
G01X301000Y317000D02*
X302600Y318600D01*
Y321000D01*
G01Y326000D02*
Y321000D01*
G01X321899Y343000D02*
X325600D01*
G01X340500Y391600D02*
X344100Y395200D01*
X351200D01*
X352200Y394200D01*
G01X350600Y332500D02*
X355000D01*
G01X360000Y402400D02*
X359200Y403200D01*
X356400D01*
G01X393300Y309200D02*
Y312500D01*
G01X379300Y309200D02*
Y305000D01*
G01X496100Y272800D02*
X493100D01*
X492500Y272200D01*
G01X527800Y265300D02*
X522400Y270700D01*
G01X555500Y237800D02*
Y236600D01*
G54D39*
X564000Y217450D03*
Y216550D03*
G54D49*
G01X29000Y282900D02*
X20000D01*
X19900Y283000D01*
G01D02*
Y287500D01*
G01Y302500D02*
X16000D01*
G01X19900Y297500D02*
X16000D01*
G01X19900Y292500D02*
Y297500D01*
G01Y307500D02*
X16000D01*
G01X36950Y302840D02*
X34160D01*
X29500Y307500D01*
X24100D01*
G01D02*
Y310900D01*
G01X33500Y282900D02*
X37400D01*
G01X60100Y73000D02*
X57700Y70600D01*
Y69700D01*
G01X54590Y266870D02*
X60670Y260790D01*
Y247320D01*
X67700Y240290D01*
Y240200D01*
G01X57500Y289000D02*
X55050Y291450D01*
Y295160D01*
G01X69800Y91100D02*
X66000D01*
G01X78800D02*
Y89600D01*
X76400Y87200D01*
G01X74300Y91100D02*
X78800D01*
G01X67400Y227100D02*
X64840Y229660D01*
Y237690D01*
X67350Y240200D01*
X67700D01*
G01X71500D02*
X67700D01*
G01X74100Y291500D02*
X78000D01*
G01X70000Y338400D02*
Y337000D01*
X72000Y335000D01*
G01X70000Y342600D02*
Y344300D01*
X72000Y346300D01*
G01X88900Y71000D02*
Y67000D01*
G01X85100Y66500D02*
Y65500D01*
X86000Y64600D01*
Y63100D01*
G01X83300Y91100D02*
X87800D01*
G01X83300D02*
Y87100D01*
G01X86000Y83300D02*
Y84400D01*
X83300Y87100D01*
G01X86000Y79100D02*
X82300D01*
X82100Y79300D01*
G01X88300Y163900D02*
X85000D01*
G01Y154900D02*
X88400D01*
G01X85000Y240200D02*
Y237200D01*
X85700Y236500D01*
G01X89600Y240200D02*
X85000D01*
G01X85800Y283100D02*
Y287452D01*
G01X91100Y345500D02*
X94000D01*
X95000Y344500D01*
G01X117380Y65870D02*
Y65860D01*
X111330Y59810D01*
G01X103800Y71800D02*
Y76240D01*
G01X103500Y309400D02*
Y306500D01*
X104500Y305500D01*
G01X105410Y318500D02*
X103500Y316590D01*
Y313600D01*
G01X99000Y350000D02*
Y355900D01*
X99500Y356400D01*
G01X113000Y360600D02*
Y361500D01*
X110500Y364000D01*
X110000D01*
G01X108500Y360600D02*
Y361610D01*
X107250Y362860D01*
Y363250D01*
X106500Y364000D01*
G01X145000Y359000D02*
Y363500D01*
X140750Y367750D01*
X127860D01*
X124500Y371110D01*
Y372500D01*
X122500Y374500D01*
X116500D01*
X115100Y373100D01*
X105500D01*
G01X125000Y76500D02*
X126820D01*
X128020Y75300D01*
X130900D01*
G01X119600Y347500D02*
X123500D01*
G01X130000Y349664D02*
X130336Y350000D01*
X133400D01*
G01X126500Y356400D02*
Y356300D01*
X128000Y354800D01*
X132000D01*
G01X124500Y352000D02*
X122000Y354500D01*
Y356400D01*
G01Y360600D02*
X121500Y361100D01*
Y363000D01*
X120000Y364500D01*
G01Y368000D02*
X119000D01*
X117000Y366000D01*
Y361100D01*
X117500Y360600D01*
G01X126500D02*
Y362500D01*
X129000Y365000D01*
G01X132000Y360200D02*
X132100Y360100D01*
X137500D01*
G01X122000Y356400D02*
X126500D01*
G01X147900Y300000D02*
Y299400D01*
X145000Y296500D01*
G01X138100Y323500D02*
X140700Y320900D01*
Y320000D01*
G01X137500Y355900D02*
X140400D01*
X140900Y355400D01*
G01X137600Y350000D02*
X142000D01*
G01X137000Y364000D02*
X137500Y363500D01*
Y360100D01*
G01X141000Y379500D02*
Y383600D01*
X142500Y385100D01*
G01X143500Y403600D02*
Y399100D01*
G01Y418000D02*
Y414200D01*
G01D02*
X142900Y413600D01*
Y410100D01*
X141800Y409000D01*
G01X174850Y338800D02*
X166700D01*
G01X163000Y350400D02*
X159100D01*
G01X174850Y353800D02*
X163800D01*
X163000Y354600D01*
G01D02*
X159100D01*
G01X174850Y343800D02*
X166700D01*
G01X167800Y392700D02*
X166600Y391500D01*
Y388500D01*
G01X158200Y377600D02*
X162600D01*
X163600Y378600D01*
G01X162400Y388500D02*
X159000D01*
X157900Y387400D01*
G01X183661Y13781D02*
Y28900D01*
G01X172400Y391000D02*
X170700Y392700D01*
X167800D01*
G01X180700Y413000D02*
Y407300D01*
X180000Y406600D01*
G01X176600Y391000D02*
Y392900D01*
X175000Y394500D01*
G01X180000Y402400D02*
Y399500D01*
X178500Y398000D01*
X177000D01*
G01X191535Y13781D02*
Y28900D01*
G01X187598Y13781D02*
Y28900D01*
G01X188500Y298100D02*
Y300000D01*
X190000Y301500D01*
G01X187300Y413000D02*
X191500D01*
G01X211220Y29380D02*
Y13781D01*
G01X215157Y29343D02*
Y13781D01*
G01X210500Y30500D02*
Y30100D01*
X211220Y29380D01*
G01X214100Y30400D02*
X215157Y29343D01*
G01X215500Y65600D02*
Y68500D01*
X215000Y69000D01*
G01X212800Y293100D02*
X208300D01*
G01X217300D02*
X212800D01*
G01X208300Y289500D02*
Y293100D01*
G01X217300Y289500D02*
Y293100D01*
G01X214600Y336000D02*
X216400D01*
X219200Y338800D01*
G01X219000Y348800D02*
X215800D01*
X214600Y350000D01*
G01D02*
X215000Y350400D01*
Y354600D01*
X214600Y355000D01*
G01X230905Y13781D02*
Y27305D01*
X232700Y29100D01*
G01X220000Y65600D02*
Y69000D01*
G01X254527Y13781D02*
Y28900D01*
G01X244619D02*
X242716Y26997D01*
Y13781D01*
G01X254000Y217400D02*
Y213500D01*
G01X241900Y235500D02*
Y238800D01*
G01X249000Y290300D02*
Y246000D01*
X250900Y244100D01*
Y237500D01*
G01D02*
X248100D01*
X246100Y235500D01*
G01X264304Y28900D02*
X262401Y26997D01*
Y13781D01*
G01X272309Y28900D02*
X274212Y26997D01*
Y13781D01*
G01X269000Y219350D02*
Y215000D01*
G01X259000Y226400D02*
Y223000D01*
G01X280052Y28900D02*
X278149Y26997D01*
Y13781D01*
G01X288057Y28900D02*
X289960Y26997D01*
Y13781D01*
G01X279000Y220600D02*
Y221010D01*
X277010Y223000D01*
X275260D01*
G01X280500Y224300D02*
X279000Y225800D01*
Y229600D01*
G01X305708Y13781D02*
Y26900D01*
X307708Y28900D01*
G01X295800D02*
X293897Y26997D01*
Y13781D01*
G01X305350Y214300D02*
X309300D01*
X312000Y217000D01*
G01X306800Y321000D02*
X310500D01*
G01X306800Y330500D02*
X310600D01*
G01X306800Y326000D02*
X310600D01*
G01X306800Y335000D02*
X310600D01*
G01X324000Y220750D02*
Y222000D01*
X330500Y228500D01*
X335600D01*
X337100Y227000D01*
Y225500D01*
G01X325600Y320500D02*
X322200D01*
G01X325600Y325000D02*
X322200D01*
G01X325600Y338500D02*
X322200D01*
G01X326000Y374000D02*
X324300Y375700D01*
X318500D01*
G01Y387900D02*
Y382300D01*
G01Y392100D02*
Y397000D01*
X320000Y398500D01*
G01X323000Y401500D02*
Y405600D01*
X324400Y407000D01*
G01X341900Y225500D02*
X337100D01*
G01X330500Y291500D02*
Y287500D01*
X328900Y285900D01*
X324500D01*
G01X339500Y286400D02*
Y282000D01*
G01X325600Y329500D02*
Y325000D01*
G01Y334000D02*
Y338500D01*
G01X330000Y411300D02*
X328600Y409900D01*
Y407000D01*
G01X334400Y409500D02*
X332600Y411300D01*
X330000D01*
G01X338600Y409500D02*
X339000Y409900D01*
X343700D01*
G01X347300Y179000D02*
X347400Y178900D01*
X350500D01*
G01Y183100D02*
Y185256D01*
X349128Y186628D01*
G01X349000Y295500D02*
X348500Y295000D01*
Y290600D01*
G01X350600Y328000D02*
X355000D01*
G01X350600Y337000D02*
X355000D01*
G01X359800Y397700D02*
Y391500D01*
X357000Y388700D01*
G01X356400Y394200D02*
Y398700D01*
G01Y407700D02*
X357900Y406200D01*
X360700D01*
G01X358100Y413000D02*
X358600Y413500D01*
X364500D01*
G01X369310Y109500D02*
X369810Y109000D01*
X370200D01*
X373200Y106000D01*
G01X369172Y102828D02*
X370028D01*
X373200Y106000D01*
G01X367400Y174400D02*
X368290Y173510D01*
X368890D01*
X370400Y172000D01*
G01X374400Y323500D02*
Y328000D01*
G01D02*
X373000D01*
X371000Y326000D01*
G01X374400Y337000D02*
X370000D01*
G01X377000Y76900D02*
X377500Y77400D01*
X380500D01*
G01X380400Y81600D02*
X377500D01*
X377000Y81100D01*
G01D02*
Y86300D01*
G01X384000Y109500D02*
X383300D01*
X379800Y106000D01*
G01X384000Y102980D02*
X382820D01*
X379800Y106000D01*
G01X391829Y129361D02*
X393235D01*
X395067Y131193D01*
G01X387193Y135130D02*
X387629Y134694D01*
Y129361D01*
G01X387193Y146942D02*
Y146943D01*
X389160Y148910D01*
G01X393098D02*
X391130Y146942D01*
G01X393098Y164658D02*
X391130Y162690D01*
G01Y154816D02*
X393098Y152848D01*
Y152847D01*
G01X387193Y178437D02*
X385500Y176744D01*
Y175570D01*
X384430Y174500D01*
G01X391130Y178437D02*
X393097Y176470D01*
X393098D01*
G01X391130Y170564D02*
X388630Y173064D01*
Y174500D01*
G01X393098Y172532D02*
X391130Y170564D01*
G01X393098Y184343D02*
X391130Y186311D01*
G01X393098Y200091D02*
X392190Y200999D01*
Y203121D01*
X393097Y204028D01*
G01X387193Y217807D02*
X389160Y215840D01*
Y215839D01*
G01X393098Y207964D02*
X391130Y205996D01*
G01D02*
X393097Y204029D01*
Y204028D01*
G01X393098Y215839D02*
X395067Y213870D01*
G01D02*
X393099Y211902D01*
X393098D01*
G01X380100Y255200D02*
X386000D01*
G01D02*
X391900D01*
G01D02*
X397800D01*
G01X383900Y375800D02*
Y372600D01*
G01Y381000D02*
Y384600D01*
G01X410816Y146942D02*
X412783Y148909D01*
Y148910D01*
G01X404910Y141036D02*
Y141037D01*
X402942Y143005D01*
G01D02*
X400975Y144972D01*
X400973D01*
G01X397035Y144973D02*
X395067Y143005D01*
G01X406879Y135130D02*
X404911Y137098D01*
X404910D01*
G01X397035Y148911D02*
X395067Y150879D01*
G01D02*
X397035Y152847D01*
X397036D01*
G01X412785Y160721D02*
X410816Y162690D01*
G01X400973Y156785D02*
X399005Y158753D01*
G01X402942Y162690D02*
X404910Y164658D01*
Y164659D01*
G01X399005Y158753D02*
X400972Y160720D01*
X400973D01*
G01X412785Y156784D02*
X412784D01*
X410816Y154816D01*
G01D02*
X412783Y152849D01*
Y152847D01*
G01X400973D02*
X399005Y150879D01*
G01D02*
X400973Y148911D01*
Y148910D01*
G01X404910Y160721D02*
X402942Y158753D01*
G01X406879Y162690D02*
X408847Y160722D01*
Y160721D01*
G01Y156784D02*
X406879Y154816D01*
G01X397036Y164658D02*
X395067Y166627D01*
G01X399005Y178437D02*
X400972Y180404D01*
Y180406D01*
G01X410816Y178437D02*
Y176016D01*
X409800Y175000D01*
G01X399005Y166627D02*
X400973Y164659D01*
Y164658D01*
G01X402942Y178437D02*
X404910Y180405D01*
Y180406D01*
G01X397035Y192217D02*
X395067Y194185D01*
G01X404910Y196155D02*
X404912D01*
X406879Y198122D01*
G01D02*
X408846Y196155D01*
Y196154D01*
G01X397036Y184343D02*
X399005Y182374D01*
G01X404910Y192217D02*
Y192216D01*
X402942Y190248D01*
G01X400973Y192217D02*
X402942Y190248D01*
G01X412784Y204028D02*
X410816Y205996D01*
G01X397035Y204028D02*
X397036D01*
X399005Y202059D01*
G01D02*
X397037Y200091D01*
X397036D01*
G01X399000Y221407D02*
X402307D01*
X402400Y221500D01*
G01X399000Y225000D02*
Y231750D01*
X398250Y232500D01*
G01X407500Y225000D02*
Y231250D01*
X408750Y232500D01*
G01X406879Y217807D02*
Y221221D01*
X406600Y221500D01*
G01X397800Y255200D02*
X403700D01*
G01D02*
X409300D01*
G01D02*
X415000D01*
G01X397800D02*
Y259300D01*
G01X403700Y255200D02*
Y259300D01*
G01X435500Y274500D02*
Y272500D01*
X432500Y269500D01*
X404000D01*
X400000Y265500D01*
G01X397300Y323900D02*
Y320700D01*
G01Y329100D02*
Y335800D01*
X398000Y336500D01*
G01Y342900D02*
Y336500D01*
G01Y347100D02*
Y352000D01*
G01X426900Y73000D02*
X423050D01*
X423000Y72950D01*
G01X427000Y77800D02*
X426900Y77700D01*
Y73000D01*
G01X427500Y91900D02*
X427400D01*
X425000Y89500D01*
Y87700D01*
G01X427000Y83200D02*
X432000Y88200D01*
Y91900D01*
G01Y96100D02*
X427500D01*
G01D02*
Y100000D01*
X427800Y100300D01*
G01X420658Y144973D02*
X422627Y146942D01*
G01D02*
X420660Y148909D01*
X420658D01*
G01Y141035D02*
X418690Y139067D01*
G01X422627Y154816D02*
X424595Y156784D01*
X424596D01*
G01X422627Y162690D02*
X424595Y164658D01*
Y164659D01*
G01X418690Y158753D02*
X420657Y160720D01*
X420658D01*
G01X426564Y158753D02*
X426911Y159100D01*
X430500D01*
G01X426564Y162690D02*
X428290D01*
X430500Y164900D01*
G01X416721Y156783D02*
X416720D01*
X414753Y154816D01*
G01Y162690D02*
X412786Y164657D01*
X412784D01*
G01X420658Y156784D02*
X418690Y154816D01*
G01D02*
X420658Y152848D01*
Y152847D01*
G01X418690Y162690D02*
X416722Y164658D01*
X416721D01*
G01Y160721D02*
X414753Y158753D01*
G01X424595Y160721D02*
X422627Y158753D01*
G01X426564Y154816D02*
X426648Y154900D01*
X430500D01*
G01X416721Y152847D02*
X414753Y150879D01*
G01X416721Y148910D02*
Y148911D01*
X414753Y150879D01*
G01X416721Y168596D02*
X418690Y166627D01*
G01D02*
X420657Y168594D01*
Y168595D01*
G01X419900Y175000D02*
Y177227D01*
X418690Y178437D01*
G01D02*
X420657Y180404D01*
Y180406D01*
G01X414753Y166627D02*
X412785Y168595D01*
X412784D01*
G01X424595D02*
X426564Y170564D01*
G01D02*
X428028Y169100D01*
X430500D01*
G01X414753Y178437D02*
X414000Y177684D01*
Y175000D01*
G01X420658Y164658D02*
X422627Y166627D01*
G01Y178437D02*
X424595Y180405D01*
Y180406D01*
G01X424100Y175000D02*
Y176964D01*
X422627Y178437D01*
G01Y190248D02*
X420660Y188281D01*
X420658D01*
G01X412784Y196154D02*
X414753Y194185D01*
G01D02*
X416721Y196153D01*
Y196154D01*
G01X426564Y198122D02*
X427142Y198700D01*
X430000D01*
G01X418690Y182374D02*
X419508Y183192D01*
Y183193D01*
X420658Y184343D01*
G01X426564Y217807D02*
X424597Y215840D01*
X424595D01*
G01X416722Y204028D02*
Y204027D01*
X418690Y202059D01*
G01D02*
X416723Y200092D01*
X416721D01*
G01X422627Y209933D02*
X424595Y211901D01*
Y211902D01*
G01X415000Y255200D02*
X420900D01*
G01X432400Y297500D02*
X427800Y292900D01*
X424900D01*
G01X417000Y342900D02*
Y337500D01*
X417500Y337000D01*
G01Y352000D02*
X417000Y351500D01*
Y347100D01*
G01X424000Y398300D02*
Y399100D01*
X419150Y403950D01*
G01X422400Y406500D02*
Y411500D01*
G01D02*
Y414400D01*
X423500Y415500D01*
G01X431100Y73000D02*
X434500Y76400D01*
Y77000D01*
G01X441500Y107900D02*
X445100D01*
X448500Y104500D01*
Y100500D01*
G01X437000Y107900D02*
X441500D01*
G01X440343Y137099D02*
X442311Y139067D01*
G01D02*
X444279Y141035D01*
X444280D01*
G01X430900Y144531D02*
X432426Y143005D01*
X434437D01*
G01D02*
X436405Y144973D01*
X436406D01*
G01X438374Y131193D02*
X440342Y133161D01*
X440343D01*
G01X446248Y146942D02*
X444280Y144974D01*
Y144973D01*
G01X436406Y148911D02*
X438374Y150879D01*
G01D02*
X436407Y152846D01*
X436406D01*
G01X442311Y154816D02*
X440564Y156564D01*
X440344Y156783D01*
X440343D01*
G01Y164657D02*
X440341D01*
X438374Y162690D01*
G01D02*
X436406Y164658D01*
Y164659D01*
G01X434437Y154816D02*
Y154236D01*
X430900Y150699D01*
Y148469D01*
G01X442311Y162690D02*
X444279Y160722D01*
X444280D01*
G01X446248Y158753D02*
X448217Y156784D01*
Y156783D01*
G01X434437Y158753D02*
X436405Y160721D01*
X436406D01*
G01X440343D02*
X442311Y158753D01*
G01X436406Y156784D02*
X438374Y154816D01*
G01X444280Y156784D02*
X446248Y154816D01*
G01X448217Y160721D02*
X446248Y162690D01*
G01D02*
X444280Y164658D01*
G01X430600Y179500D02*
Y175800D01*
X432300Y174100D01*
G01X434437Y170564D02*
X432300Y172701D01*
Y174100D01*
G01X446248Y166627D02*
X448217Y164658D01*
X448218D01*
G01X446511Y175500D02*
Y178174D01*
X446248Y178437D01*
G01X440344Y180406D02*
Y180407D01*
X442311Y182374D01*
G01X444280Y180405D02*
X442311Y182374D01*
G01X448217Y180405D02*
X448216D01*
X446248Y178437D01*
G01X440343Y168595D02*
X442311Y166627D01*
G01X434437Y178437D02*
X436500Y176374D01*
Y174100D01*
G01X436406Y180406D02*
X434437Y178437D01*
G01X446248Y170564D02*
X444280Y168596D01*
Y168595D01*
G01X442311Y178437D02*
Y175500D01*
G01X440342Y192217D02*
X438374Y194185D01*
G01X446248Y190248D02*
X444280Y192216D01*
Y192217D01*
G01X448216Y192216D02*
X446248Y190248D01*
G01X431006Y189780D02*
Y189742D01*
X434437Y186311D01*
G01D02*
X431826Y183700D01*
X430600D01*
G01X448216Y207965D02*
X446248Y209933D01*
G01X434437Y205996D02*
X431341Y202900D01*
X430000D01*
G01X440343Y215839D02*
X438374Y213870D01*
G01X440343Y219777D02*
X442566Y222000D01*
X445485D01*
G01X444000Y226000D02*
X445681Y224319D01*
Y222196D01*
X445485Y222000D01*
G01X444000Y246100D02*
X448500D01*
G01X444000D02*
Y250000D01*
G01X439500Y246100D02*
Y250000D01*
G01X445600Y278300D02*
X448900Y275000D01*
X455000D01*
X456600Y276600D01*
Y279500D01*
G01X439600Y396500D02*
X443000D01*
G01X435400D02*
X432000D01*
G01X463500Y86500D02*
X464400D01*
X469400Y91500D01*
G01Y96500D02*
X468000D01*
X463500Y92000D01*
G01X454600Y108500D02*
X453000Y110100D01*
Y113900D01*
G01X458500D02*
X453000D01*
G01X452154Y141035D02*
Y141037D01*
X454122Y143005D01*
G01D02*
X456090Y141037D01*
Y141035D01*
G01X450185Y135130D02*
X452152Y137097D01*
X452154D01*
G01X460028Y141035D02*
X461996Y139067D01*
G01X460028Y156785D02*
X461996Y158753D01*
G01X450185Y162690D02*
X452152Y164657D01*
X452154D01*
G01X461996Y158753D02*
X463964Y156785D01*
Y156784D01*
G01X458059Y150879D02*
X460027Y152847D01*
X460028D01*
G01X450185Y170564D02*
X448218Y168597D01*
Y168595D01*
G01X460027D02*
X458059Y166627D01*
G01X454123Y170564D02*
Y174112D01*
X455511Y175500D01*
G01X450185Y166627D02*
X452153Y168595D01*
X452154D01*
G01Y180406D02*
X450185Y178437D01*
G01D02*
Y176626D01*
X451311Y175500D01*
G01X461996Y182374D02*
X463964Y180406D01*
X463965D01*
G01Y168595D02*
X465933Y166627D01*
G01X454122Y186311D02*
X452155Y184344D01*
X452154D01*
G01X463965Y188281D02*
X463966D01*
X465933Y190248D01*
G01D02*
X463966Y192215D01*
Y192217D01*
G01X448216Y196154D02*
X448217D01*
X450185Y198122D01*
G01X456091Y188280D02*
X454122Y186311D01*
G01X463965Y184343D02*
X461996Y182374D01*
G01X460028Y196154D02*
X458059Y194185D01*
G01D02*
X460027Y192217D01*
X460028D01*
G01Y184343D02*
Y184342D01*
X461996Y182374D01*
G01X454122Y205996D02*
X452154Y207964D01*
Y207965D01*
G01X450185Y217807D02*
X449685Y218307D01*
Y222000D01*
G01X462000Y246100D02*
Y250000D01*
G01X457500Y246100D02*
X453000D01*
G01X457500D02*
Y250000D01*
G01X456600Y284500D02*
X460000D01*
G01X456600Y289500D02*
X460000D01*
G01X476666Y138867D02*
X479867D01*
G01X473807Y143005D02*
X474007Y142805D01*
X476666D01*
G01X467902Y156784D02*
X469870Y154816D01*
G01Y178437D02*
X468754Y179554D01*
X467903Y180404D01*
Y180406D01*
G01X471839Y168595D02*
X473807Y166627D01*
G01X468100Y175500D02*
Y176667D01*
X469870Y178437D01*
G01X475777Y200091D02*
X475909D01*
X478000Y198000D01*
G01X481500Y182016D02*
X481320D01*
X481225Y182111D01*
X478000D01*
G01X471839Y200091D02*
X469870Y198122D01*
G01X478000Y186311D02*
X473807D01*
G01X469870Y217807D02*
X467903Y215840D01*
X467902D01*
G01X471839D02*
X471837D01*
X469870Y217807D01*
G01X471840Y207965D02*
Y207963D01*
X473807Y205996D01*
G01X467902Y211902D02*
X465933Y209933D01*
G01X493300Y121500D02*
Y126300D01*
G01D02*
X489400D01*
G01X492600Y163000D02*
X496000D01*
G01X492600Y167500D02*
X496000D01*
G01X497000Y175000D02*
X495500Y176500D01*
X492600D01*
G01Y197500D02*
X496500D01*
G01X488400Y202500D02*
X485239D01*
X485000Y202739D01*
G01X495000Y346000D02*
X493250Y344250D01*
Y339446D01*
X495446Y337250D01*
X499250D01*
X519000Y317500D01*
Y307500D01*
G01X498900Y345500D02*
X495500D01*
X495000Y346000D01*
G01X503900Y128690D02*
X502290D01*
X499900Y126300D01*
G01X503860Y124150D02*
X502050D01*
X499900Y126300D01*
G01X526500Y67500D02*
Y75500D01*
X533000Y82000D01*
G01X524900Y99000D02*
Y100900D01*
X532500Y108500D01*
X553000D01*
G01X528710Y227500D02*
X538900D01*
G01X527800Y261100D02*
Y260130D01*
X530350Y257580D01*
Y257480D01*
G01X527300Y420101D02*
X523601D01*
X522100Y418600D01*
Y416500D01*
G01X540400Y69000D02*
X537000D01*
G01X547211Y209800D02*
Y208101D01*
X548712Y206600D01*
X551000D01*
G01Y212900D02*
X549000D01*
X547211Y211111D01*
Y209800D01*
G01X551000Y202400D02*
X554600D01*
G01X551000Y217100D02*
Y219900D01*
X548300Y222600D01*
G01X546500Y236600D02*
Y240500D01*
G01X545250Y267950D02*
X548550D01*
X549000Y267500D01*
G01X545200Y281300D02*
X541200D01*
X541000Y281500D01*
G01X545200Y296450D02*
X542000D01*
G01X537500Y304000D02*
X540000Y306500D01*
X544800D01*
X545200Y306100D01*
G01X543500Y421900D02*
Y416600D01*
G01Y421900D02*
X555500D01*
G01Y60800D02*
X552800D01*
X551597Y59597D01*
X551500D01*
G01X555700Y74700D02*
Y79700D01*
G01X568700Y199000D02*
X564100D01*
X563100Y198000D01*
G01X558900D02*
Y202500D01*
G01X554400Y272100D02*
Y267500D01*
G01X618650Y249300D02*
X591700D01*
X586500Y254500D01*
X562370D01*
X562000Y254870D01*
G01X572000Y385700D02*
X568300D01*
X567500Y386500D01*
G01Y408400D02*
Y403000D01*
G01X552900Y407000D02*
Y404100D01*
X555000Y402000D01*
G01X555500Y421900D02*
X567000D01*
G01D02*
X579000D01*
G01X577200Y65800D02*
X580500D01*
G01X582500Y79600D02*
X585900D01*
G01X575300Y199000D02*
Y202200D01*
X573200Y204300D01*
G01X578900Y236600D02*
X575400D01*
G01D02*
X574800Y237200D01*
X570000D01*
G01X581500Y267000D02*
X577500D01*
X574250Y263750D01*
G01X573750Y292250D02*
X581400D01*
G01X576200Y390700D02*
Y385700D01*
G01D02*
X580300D01*
G01X576900Y407500D02*
Y403100D01*
G01X579000Y421900D02*
X584000D01*
G01X596902Y190865D02*
X597703Y190064D01*
Y187000D01*
G01X591902Y190865D02*
Y189101D01*
X594003Y187000D01*
G01X601902Y195065D02*
X606902D01*
G01X602500Y408900D02*
Y404000D01*
G01X591000Y408900D02*
Y404000D01*
G01X614000Y421900D02*
X602700D01*
G01D02*
X597500D01*
G01X621000Y196774D02*
X618400D01*
X616500Y194874D01*
G01X610500Y190500D02*
Y194000D01*
X609435Y195065D01*
X606902D01*
G01X614500Y409400D02*
Y403500D01*
G01X625800Y215874D02*
X627500Y214174D01*
Y205374D01*
G01X633500Y205906D02*
Y204874D01*
X630000Y201374D01*
Y200974D01*
G01X642100Y96500D02*
Y102000D01*
G01Y108000D02*
Y102000D01*
G01Y108000D02*
Y108600D01*
X647000Y113500D01*
M02*
